(kicad_sch
	(version 20250114)
	(generator "eeschema")
	(generator_version "9.0")
	(paper "A3")
	(title_block
		(title "OCuLink to 10GbE adapter")
		(date "2026-02-23")
		(rev "1.1.0")
		(company "Antmicro Ltd")
		(comment 1 "www.antmicro.com")
	)
	(bus_alias "CLK"
		(members "+" "-")
	)
	(bus_alias "JTAG"
		(members "~{JRST}" "JTCK" "JTMS" "JTDI" "JTDO")
	)
	(bus_alias "PCIe"
		(members "TX3+" "TX3-" "TX2+" "TX2-" "TX1+" "TX1-" "TX0+" "TX0-" "RX3+"
			"RX3-" "RX2+" "RX2-" "RX1+" "RX1-" "RX0+" "RX0-"
		)
	)
	(text "X710-AT2 PCIe Interface"
		(exclude_from_sim no)
		(at 215.9 50.8 0)
		(effects
			(font
				(size 2.54 2.54)
				(thickness 0.508)
				(bold yes)
			)
		)
	)
	(text_box "NOTE: Place this resistor close to the controller;\nthe trace length should be less than 25.4 mm."
		(exclude_from_sim no)
		(at 231.14 223.52 0)
		(size 50.8 6.35)
		(margins 0.9525 0.9525 0.9525 0.9525)
		(stroke
			(width 0)
			(type solid)
		)
		(fill
			(type none)
		)
		(effects
			(font
				(size 1.27 1.27)
			)
		)
	)
	(text_box "JTAG Debug Connector"
		(exclude_from_sim no)
		(at 254 129.54 0)
		(size 73.66 29.21)
		(margins 0.9525 0.9525 0.9525 0.9525)
		(stroke
			(width 0)
			(type solid)
		)
		(fill
			(type none)
		)
		(effects
			(font
				(size 1.27 1.27)
			)
			(justify left top)
		)
	)
	(junction
		(at 167.64 255.27)
		(diameter 0)
		(color 0 0 0 0)
	)
	(junction
		(at 224.79 257.81)
		(diameter 0)
		(color 0 0 0 0)
	)
	(junction
		(at 245.11 95.25)
		(diameter 0)
		(color 0 0 0 0)
	)
	(junction
		(at 262.89 90.17)
		(diameter 0)
		(color 0 0 0 0)
	)
	(junction
		(at 232.41 255.27)
		(diameter 0)
		(color 0 0 0 0)
	)
	(junction
		(at 254 74.93)
		(diameter 0)
		(color 0 0 0 0)
	)
	(junction
		(at 254 92.71)
		(diameter 0)
		(color 0 0 0 0)
	)
	(junction
		(at 236.22 97.79)
		(diameter 0)
		(color 0 0 0 0)
	)
	(junction
		(at 245.11 74.93)
		(diameter 0)
		(color 0 0 0 0)
	)
	(junction
		(at 271.78 149.86)
		(diameter 0)
		(color 0 0 0 0)
	)
	(junction
		(at 271.78 87.63)
		(diameter 0)
		(color 0 0 0 0)
	)
	(junction
		(at 163.83 255.27)
		(diameter 0)
		(color 0 0 0 0)
	)
	(no_connect
		(at 198.12 166.37)
	)
	(no_connect
		(at 198.12 181.61)
	)
	(no_connect
		(at 198.12 212.09)
	)
	(no_connect
		(at 198.12 204.47)
	)
	(no_connect
		(at 198.12 163.83)
	)
	(no_connect
		(at 198.12 219.71)
	)
	(no_connect
		(at 274.32 139.7)
	)
	(no_connect
		(at 198.12 194.31)
	)
	(no_connect
		(at 198.12 171.45)
	)
	(no_connect
		(at 198.12 217.17)
	)
	(no_connect
		(at 198.12 186.69)
	)
	(no_connect
		(at 198.12 179.07)
	)
	(no_connect
		(at 198.12 189.23)
	)
	(no_connect
		(at 198.12 196.85)
	)
	(no_connect
		(at 198.12 173.99)
	)
	(no_connect
		(at 198.12 201.93)
	)
	(no_connect
		(at 198.12 209.55)
	)
	(bus_entry
		(at 140.97 138.43)
		(size 2.54 -2.54)
		(stroke
			(width 0)
			(type default)
		)
	)
	(bus_entry
		(at 140.97 146.05)
		(size 2.54 -2.54)
		(stroke
			(width 0)
			(type default)
		)
	)
	(bus_entry
		(at 140.97 161.29)
		(size 2.54 -2.54)
		(stroke
			(width 0)
			(type default)
		)
	)
	(bus_entry
		(at 140.97 120.65)
		(size 2.54 -2.54)
		(stroke
			(width 0)
			(type default)
		)
	)
	(bus_entry
		(at 140.97 153.67)
		(size 2.54 -2.54)
		(stroke
			(width 0)
			(type default)
		)
	)
	(bus_entry
		(at 140.97 107.95)
		(size 2.54 -2.54)
		(stroke
			(width 0)
			(type default)
		)
	)
	(bus_entry
		(at 140.97 143.51)
		(size 2.54 -2.54)
		(stroke
			(width 0)
			(type default)
		)
	)
	(bus_entry
		(at 140.97 113.03)
		(size 2.54 -2.54)
		(stroke
			(width 0)
			(type default)
		)
	)
	(bus_entry
		(at 140.97 115.57)
		(size 2.54 -2.54)
		(stroke
			(width 0)
			(type default)
		)
	)
	(bus_entry
		(at 140.97 158.75)
		(size 2.54 -2.54)
		(stroke
			(width 0)
			(type default)
		)
	)
	(bus_entry
		(at 140.97 135.89)
		(size 2.54 -2.54)
		(stroke
			(width 0)
			(type default)
		)
	)
	(bus_entry
		(at 140.97 151.13)
		(size 2.54 -2.54)
		(stroke
			(width 0)
			(type default)
		)
	)
	(bus_entry
		(at 140.97 97.79)
		(size 2.54 -2.54)
		(stroke
			(width 0)
			(type default)
		)
	)
	(bus_entry
		(at 140.97 130.81)
		(size 2.54 -2.54)
		(stroke
			(width 0)
			(type default)
		)
	)
	(bus_entry
		(at 140.97 105.41)
		(size 2.54 -2.54)
		(stroke
			(width 0)
			(type default)
		)
	)
	(bus_entry
		(at 140.97 100.33)
		(size 2.54 -2.54)
		(stroke
			(width 0)
			(type default)
		)
	)
	(bus_entry
		(at 140.97 123.19)
		(size 2.54 -2.54)
		(stroke
			(width 0)
			(type default)
		)
	)
	(bus_entry
		(at 140.97 128.27)
		(size 2.54 -2.54)
		(stroke
			(width 0)
			(type default)
		)
	)
	(bus
		(pts
			(xy 140.97 130.81) (xy 140.97 135.89)
		)
		(stroke
			(width 0)
			(type default)
		)
	)
	(bus
		(pts
			(xy 140.97 128.27) (xy 140.97 130.81)
		)
		(stroke
			(width 0)
			(type default)
		)
	)
	(wire
		(pts
			(xy 233.68 92.71) (xy 254 92.71)
		)
		(stroke
			(width 0)
			(type default)
		)
	)
	(wire
		(pts
			(xy 143.51 143.51) (xy 198.12 143.51)
		)
		(stroke
			(width 0)
			(type default)
		)
	)
	(bus
		(pts
			(xy 140.97 135.89) (xy 140.97 138.43)
		)
		(stroke
			(width 0)
			(type default)
		)
	)
	(wire
		(pts
			(xy 232.41 255.27) (xy 232.41 260.35)
		)
		(stroke
			(width 0)
			(type default)
		)
	)
	(bus
		(pts
			(xy 140.97 143.51) (xy 140.97 146.05)
		)
		(stroke
			(width 0)
			(type default)
		)
	)
	(wire
		(pts
			(xy 143.51 151.13) (xy 160.02 151.13)
		)
		(stroke
			(width 0)
			(type default)
		)
	)
	(bus
		(pts
			(xy 140.97 138.43) (xy 140.97 143.51)
		)
		(stroke
			(width 0)
			(type default)
		)
	)
	(wire
		(pts
			(xy 236.22 77.47) (xy 236.22 74.93)
		)
		(stroke
			(width 0)
			(type default)
		)
	)
	(wire
		(pts
			(xy 271.78 106.68) (xy 271.78 109.22)
		)
		(stroke
			(width 0)
			(type default)
		)
	)
	(wire
		(pts
			(xy 143.51 128.27) (xy 198.12 128.27)
		)
		(stroke
			(width 0)
			(type default)
		)
	)
	(wire
		(pts
			(xy 254 72.39) (xy 254 74.93)
		)
		(stroke
			(width 0)
			(type default)
		)
	)
	(wire
		(pts
			(xy 156.21 87.63) (xy 198.12 87.63)
		)
		(stroke
			(width 0)
			(type default)
		)
	)
	(bus
		(pts
			(xy 140.97 151.13) (xy 140.97 153.67)
		)
		(stroke
			(width 0)
			(type default)
		)
	)
	(wire
		(pts
			(xy 236.22 82.55) (xy 236.22 97.79)
		)
		(stroke
			(width 0)
			(type default)
		)
	)
	(wire
		(pts
			(xy 224.79 257.81) (xy 224.79 260.35)
		)
		(stroke
			(width 0)
			(type default)
		)
	)
	(wire
		(pts
			(xy 233.68 97.79) (xy 236.22 97.79)
		)
		(stroke
			(width 0)
			(type default)
		)
	)
	(wire
		(pts
			(xy 262.89 90.17) (xy 290.83 90.17)
		)
		(stroke
			(width 0)
			(type default)
		)
	)
	(wire
		(pts
			(xy 274.32 149.86) (xy 271.78 149.86)
		)
		(stroke
			(width 0)
			(type default)
		)
	)
	(wire
		(pts
			(xy 220.98 255.27) (xy 232.41 255.27)
		)
		(stroke
			(width 0)
			(type default)
		)
	)
	(bus
		(pts
			(xy 140.97 120.65) (xy 140.97 123.19)
		)
		(stroke
			(width 0)
			(type default)
		)
	)
	(wire
		(pts
			(xy 254 92.71) (xy 290.83 92.71)
		)
		(stroke
			(width 0)
			(type default)
		)
	)
	(wire
		(pts
			(xy 325.12 144.78) (xy 306.07 144.78)
		)
		(stroke
			(width 0)
			(type default)
		)
	)
	(wire
		(pts
			(xy 255.27 142.24) (xy 274.32 142.24)
		)
		(stroke
			(width 0)
			(type default)
		)
	)
	(wire
		(pts
			(xy 165.1 135.89) (xy 198.12 135.89)
		)
		(stroke
			(width 0)
			(type default)
		)
	)
	(wire
		(pts
			(xy 325.12 149.86) (xy 306.07 149.86)
		)
		(stroke
			(width 0)
			(type default)
		)
	)
	(wire
		(pts
			(xy 143.51 125.73) (xy 198.12 125.73)
		)
		(stroke
			(width 0)
			(type default)
		)
	)
	(wire
		(pts
			(xy 167.64 257.81) (xy 171.45 257.81)
		)
		(stroke
			(width 0)
			(type default)
		)
	)
	(wire
		(pts
			(xy 180.34 260.35) (xy 181.61 260.35)
		)
		(stroke
			(width 0)
			(type default)
		)
	)
	(bus
		(pts
			(xy 140.97 97.79) (xy 140.97 100.33)
		)
		(stroke
			(width 0)
			(type default)
		)
	)
	(wire
		(pts
			(xy 163.83 255.27) (xy 163.83 256.54)
		)
		(stroke
			(width 0)
			(type default)
		)
	)
	(wire
		(pts
			(xy 271.78 149.86) (xy 271.78 152.4)
		)
		(stroke
			(width 0)
			(type default)
		)
	)
	(wire
		(pts
			(xy 236.22 97.79) (xy 290.83 97.79)
		)
		(stroke
			(width 0)
			(type default)
		)
	)
	(wire
		(pts
			(xy 255.27 147.32) (xy 274.32 147.32)
		)
		(stroke
			(width 0)
			(type default)
		)
	)
	(wire
		(pts
			(xy 200.66 255.27) (xy 215.9 255.27)
		)
		(stroke
			(width 0)
			(type default)
		)
	)
	(wire
		(pts
			(xy 233.68 217.17) (xy 243.84 217.17)
		)
		(stroke
			(width 0)
			(type default)
		)
	)
	(wire
		(pts
			(xy 143.51 102.87) (xy 168.91 102.87)
		)
		(stroke
			(width 0)
			(type default)
		)
	)
	(wire
		(pts
			(xy 163.83 254) (xy 163.83 255.27)
		)
		(stroke
			(width 0)
			(type default)
		)
	)
	(bus
		(pts
			(xy 140.97 100.33) (xy 140.97 102.87)
		)
		(stroke
			(width 0)
			(type default)
		)
	)
	(wire
		(pts
			(xy 262.89 106.68) (xy 262.89 109.22)
		)
		(stroke
			(width 0)
			(type default)
		)
	)
	(wire
		(pts
			(xy 274.32 144.78) (xy 271.78 144.78)
		)
		(stroke
			(width 0)
			(type default)
		)
	)
	(wire
		(pts
			(xy 173.99 118.11) (xy 198.12 118.11)
		)
		(stroke
			(width 0)
			(type default)
		)
	)
	(wire
		(pts
			(xy 308.61 142.24) (xy 306.07 142.24)
		)
		(stroke
			(width 0)
			(type default)
		)
	)
	(bus
		(pts
			(xy 140.97 158.75) (xy 140.97 161.29)
		)
		(stroke
			(width 0)
			(type default)
		)
	)
	(wire
		(pts
			(xy 143.51 97.79) (xy 162.56 97.79)
		)
		(stroke
			(width 0)
			(type default)
		)
	)
	(wire
		(pts
			(xy 167.64 255.27) (xy 181.61 255.27)
		)
		(stroke
			(width 0)
			(type default)
		)
	)
	(wire
		(pts
			(xy 232.41 255.27) (xy 250.19 255.27)
		)
		(stroke
			(width 0)
			(type default)
		)
	)
	(wire
		(pts
			(xy 143.51 105.41) (xy 160.02 105.41)
		)
		(stroke
			(width 0)
			(type default)
		)
	)
	(wire
		(pts
			(xy 251.46 217.17) (xy 251.46 219.71)
		)
		(stroke
			(width 0)
			(type default)
		)
	)
	(wire
		(pts
			(xy 143.51 95.25) (xy 162.56 95.25)
		)
		(stroke
			(width 0)
			(type default)
		)
	)
	(wire
		(pts
			(xy 233.68 87.63) (xy 271.78 87.63)
		)
		(stroke
			(width 0)
			(type default)
		)
	)
	(wire
		(pts
			(xy 165.1 120.65) (xy 198.12 120.65)
		)
		(stroke
			(width 0)
			(type default)
		)
	)
	(wire
		(pts
			(xy 143.51 156.21) (xy 198.12 156.21)
		)
		(stroke
			(width 0)
			(type default)
		)
	)
	(wire
		(pts
			(xy 245.11 82.55) (xy 245.11 95.25)
		)
		(stroke
			(width 0)
			(type default)
		)
	)
	(wire
		(pts
			(xy 262.89 90.17) (xy 262.89 101.6)
		)
		(stroke
			(width 0)
			(type default)
		)
	)
	(bus
		(pts
			(xy 140.97 161.29) (xy 140.97 163.83)
		)
		(stroke
			(width 0)
			(type default)
		)
	)
	(wire
		(pts
			(xy 200.66 257.81) (xy 215.9 257.81)
		)
		(stroke
			(width 0)
			(type default)
		)
	)
	(wire
		(pts
			(xy 156.21 90.17) (xy 198.12 90.17)
		)
		(stroke
			(width 0)
			(type default)
		)
	)
	(wire
		(pts
			(xy 143.51 140.97) (xy 198.12 140.97)
		)
		(stroke
			(width 0)
			(type default)
		)
	)
	(wire
		(pts
			(xy 165.1 105.41) (xy 198.12 105.41)
		)
		(stroke
			(width 0)
			(type default)
		)
	)
	(bus
		(pts
			(xy 135.89 166.37) (xy 138.43 166.37)
		)
		(stroke
			(width 0)
			(type default)
		)
	)
	(wire
		(pts
			(xy 255.27 255.27) (xy 264.16 255.27)
		)
		(stroke
			(width 0)
			(type default)
		)
	)
	(bus
		(pts
			(xy 140.97 113.03) (xy 140.97 115.57)
		)
		(stroke
			(width 0)
			(type default)
		)
	)
	(wire
		(pts
			(xy 254 74.93) (xy 254 77.47)
		)
		(stroke
			(width 0)
			(type default)
		)
	)
	(wire
		(pts
			(xy 325.12 139.7) (xy 306.07 139.7)
		)
		(stroke
			(width 0)
			(type default)
		)
	)
	(wire
		(pts
			(xy 245.11 74.93) (xy 245.11 77.47)
		)
		(stroke
			(width 0)
			(type default)
		)
	)
	(wire
		(pts
			(xy 163.83 261.62) (xy 163.83 262.89)
		)
		(stroke
			(width 0)
			(type default)
		)
	)
	(bus
		(pts
			(xy 140.97 107.95) (xy 140.97 113.03)
		)
		(stroke
			(width 0)
			(type default)
		)
	)
	(bus
		(pts
			(xy 138.43 166.37) (xy 140.97 163.83)
		)
		(stroke
			(width 0)
			(type default)
		)
	)
	(wire
		(pts
			(xy 143.51 148.59) (xy 168.91 148.59)
		)
		(stroke
			(width 0)
			(type default)
		)
	)
	(bus
		(pts
			(xy 140.97 115.57) (xy 140.97 120.65)
		)
		(stroke
			(width 0)
			(type default)
		)
	)
	(wire
		(pts
			(xy 143.51 110.49) (xy 198.12 110.49)
		)
		(stroke
			(width 0)
			(type default)
		)
	)
	(wire
		(pts
			(xy 143.51 118.11) (xy 168.91 118.11)
		)
		(stroke
			(width 0)
			(type default)
		)
	)
	(wire
		(pts
			(xy 143.51 133.35) (xy 168.91 133.35)
		)
		(stroke
			(width 0)
			(type default)
		)
	)
	(wire
		(pts
			(xy 143.51 113.03) (xy 198.12 113.03)
		)
		(stroke
			(width 0)
			(type default)
		)
	)
	(wire
		(pts
			(xy 176.53 257.81) (xy 181.61 257.81)
		)
		(stroke
			(width 0)
			(type default)
		)
	)
	(wire
		(pts
			(xy 233.68 95.25) (xy 245.11 95.25)
		)
		(stroke
			(width 0)
			(type default)
		)
	)
	(wire
		(pts
			(xy 233.68 90.17) (xy 262.89 90.17)
		)
		(stroke
			(width 0)
			(type default)
		)
	)
	(wire
		(pts
			(xy 271.78 144.78) (xy 271.78 149.86)
		)
		(stroke
			(width 0)
			(type default)
		)
	)
	(bus
		(pts
			(xy 140.97 146.05) (xy 140.97 151.13)
		)
		(stroke
			(width 0)
			(type default)
		)
	)
	(wire
		(pts
			(xy 255.27 257.81) (xy 264.16 257.81)
		)
		(stroke
			(width 0)
			(type default)
		)
	)
	(wire
		(pts
			(xy 308.61 152.4) (xy 308.61 142.24)
		)
		(stroke
			(width 0)
			(type default)
		)
	)
	(wire
		(pts
			(xy 163.83 255.27) (xy 167.64 255.27)
		)
		(stroke
			(width 0)
			(type default)
		)
	)
	(wire
		(pts
			(xy 173.99 102.87) (xy 198.12 102.87)
		)
		(stroke
			(width 0)
			(type default)
		)
	)
	(wire
		(pts
			(xy 271.78 87.63) (xy 271.78 101.6)
		)
		(stroke
			(width 0)
			(type default)
		)
	)
	(wire
		(pts
			(xy 224.79 257.81) (xy 250.19 257.81)
		)
		(stroke
			(width 0)
			(type default)
		)
	)
	(bus
		(pts
			(xy 140.97 123.19) (xy 140.97 128.27)
		)
		(stroke
			(width 0)
			(type default)
		)
	)
	(wire
		(pts
			(xy 236.22 74.93) (xy 245.11 74.93)
		)
		(stroke
			(width 0)
			(type default)
		)
	)
	(wire
		(pts
			(xy 233.68 219.71) (xy 251.46 219.71)
		)
		(stroke
			(width 0)
			(type default)
		)
	)
	(bus
		(pts
			(xy 140.97 105.41) (xy 140.97 107.95)
		)
		(stroke
			(width 0)
			(type default)
		)
	)
	(wire
		(pts
			(xy 245.11 95.25) (xy 290.83 95.25)
		)
		(stroke
			(width 0)
			(type default)
		)
	)
	(wire
		(pts
			(xy 167.64 97.79) (xy 198.12 97.79)
		)
		(stroke
			(width 0)
			(type default)
		)
	)
	(wire
		(pts
			(xy 248.92 217.17) (xy 251.46 217.17)
		)
		(stroke
			(width 0)
			(type default)
		)
	)
	(wire
		(pts
			(xy 245.11 74.93) (xy 254 74.93)
		)
		(stroke
			(width 0)
			(type default)
		)
	)
	(wire
		(pts
			(xy 271.78 87.63) (xy 290.83 87.63)
		)
		(stroke
			(width 0)
			(type default)
		)
	)
	(wire
		(pts
			(xy 143.51 158.75) (xy 198.12 158.75)
		)
		(stroke
			(width 0)
			(type default)
		)
	)
	(wire
		(pts
			(xy 165.1 151.13) (xy 198.12 151.13)
		)
		(stroke
			(width 0)
			(type default)
		)
	)
	(wire
		(pts
			(xy 173.99 148.59) (xy 198.12 148.59)
		)
		(stroke
			(width 0)
			(type default)
		)
	)
	(bus
		(pts
			(xy 135.89 105.41) (xy 138.43 105.41)
		)
		(stroke
			(width 0)
			(type default)
		)
	)
	(bus
		(pts
			(xy 140.97 153.67) (xy 140.97 158.75)
		)
		(stroke
			(width 0)
			(type default)
		)
	)
	(wire
		(pts
			(xy 180.34 261.62) (xy 180.34 260.35)
		)
		(stroke
			(width 0)
			(type default)
		)
	)
	(bus
		(pts
			(xy 138.43 105.41) (xy 140.97 102.87)
		)
		(stroke
			(width 0)
			(type default)
		)
	)
	(wire
		(pts
			(xy 220.98 257.81) (xy 224.79 257.81)
		)
		(stroke
			(width 0)
			(type default)
		)
	)
	(wire
		(pts
			(xy 143.51 120.65) (xy 160.02 120.65)
		)
		(stroke
			(width 0)
			(type default)
		)
	)
	(wire
		(pts
			(xy 143.51 135.89) (xy 160.02 135.89)
		)
		(stroke
			(width 0)
			(type default)
		)
	)
	(wire
		(pts
			(xy 254 82.55) (xy 254 92.71)
		)
		(stroke
			(width 0)
			(type default)
		)
	)
	(wire
		(pts
			(xy 167.64 95.25) (xy 198.12 95.25)
		)
		(stroke
			(width 0)
			(type default)
		)
	)
	(wire
		(pts
			(xy 167.64 257.81) (xy 167.64 255.27)
		)
		(stroke
			(width 0)
			(type default)
		)
	)
	(wire
		(pts
			(xy 173.99 133.35) (xy 198.12 133.35)
		)
		(stroke
			(width 0)
			(type default)
		)
	)
	(label "PCIe_{x4}.TX3-"
		(at 156.21 151.13 180)
		(effects
			(font
				(size 1.27 1.27)
			)
			(justify right bottom)
		)
	)
	(label "PCIe_JTAG.~{JRST}"
		(at 290.83 87.63 180)
		(effects
			(font
				(size 1.27 1.27)
			)
			(justify right bottom)
		)
	)
	(label "PCIe_JTAG.JTDI"
		(at 290.83 95.25 180)
		(effects
			(font
				(size 1.27 1.27)
			)
			(justify right bottom)
		)
	)
	(label "PCIe_JTAG.JTMS"
		(at 255.27 142.24 0)
		(effects
			(font
				(size 1.27 1.27)
			)
			(justify left bottom)
		)
	)
	(label "PCIe_JTAG.JTMS"
		(at 290.83 92.71 180)
		(effects
			(font
				(size 1.27 1.27)
			)
			(justify right bottom)
		)
	)
	(label "RSENSE"
		(at 234.95 219.71 0)
		(effects
			(font
				(size 1.27 1.27)
			)
			(justify left bottom)
		)
	)
	(label "PCIe_{x4}.RX3-"
		(at 156.21 158.75 180)
		(effects
			(font
				(size 1.27 1.27)
			)
			(justify right bottom)
		)
	)
	(label "PCIe_{x4}.TX1+"
		(at 156.21 118.11 180)
		(effects
			(font
				(size 1.27 1.27)
			)
			(justify right bottom)
		)
	)
	(label "PCIe_{x4}.TX1-"
		(at 156.21 120.65 180)
		(effects
			(font
				(size 1.27 1.27)
			)
			(justify right bottom)
		)
	)
	(label "CLK+"
		(at 264.16 255.27 180)
		(effects
			(font
				(size 1.27 1.27)
			)
			(justify right bottom)
		)
	)
	(label "PCIe_{x4}.TX2-"
		(at 156.21 135.89 180)
		(effects
			(font
				(size 1.27 1.27)
			)
			(justify right bottom)
		)
	)
	(label "GEN_CLK-"
		(at 210.82 257.81 180)
		(effects
			(font
				(size 1.27 1.27)
			)
			(justify right bottom)
		)
	)
	(label "PCIe_{x4}_AC.TX0-"
		(at 195.58 105.41 180)
		(effects
			(font
				(size 1.27 1.27)
			)
			(justify right bottom)
		)
	)
	(label "REFCLK.-"
		(at 156.21 97.79 180)
		(effects
			(font
				(size 1.27 1.27)
			)
			(justify right bottom)
		)
	)
	(label "PCIe_{x4}.TX0+"
		(at 156.21 102.87 180)
		(effects
			(font
				(size 1.27 1.27)
			)
			(justify right bottom)
		)
	)
	(label "PCIe_{x4}.RX0+"
		(at 156.21 110.49 180)
		(effects
			(font
				(size 1.27 1.27)
			)
			(justify right bottom)
		)
	)
	(label "GEN_F_CLK+"
		(at 245.11 255.27 180)
		(effects
			(font
				(size 1.27 1.27)
			)
			(justify right bottom)
		)
	)
	(label "PCIe_{x4}_AC.TX0+"
		(at 195.58 102.87 180)
		(effects
			(font
				(size 1.27 1.27)
			)
			(justify right bottom)
		)
	)
	(label "PCIe_{x4}.TX3+"
		(at 156.21 148.59 180)
		(effects
			(font
				(size 1.27 1.27)
			)
			(justify right bottom)
		)
	)
	(label "PCIe_{x4}_AC.TX2-"
		(at 195.58 135.89 180)
		(effects
			(font
				(size 1.27 1.27)
			)
			(justify right bottom)
		)
	)
	(label "CLK-"
		(at 264.16 257.81 180)
		(effects
			(font
				(size 1.27 1.27)
			)
			(justify right bottom)
		)
	)
	(label "PCIe_{x4}.RX1+"
		(at 156.21 125.73 180)
		(effects
			(font
				(size 1.27 1.27)
			)
			(justify right bottom)
		)
	)
	(label "PCIe_JTAG.JTCK"
		(at 290.83 90.17 180)
		(effects
			(font
				(size 1.27 1.27)
			)
			(justify right bottom)
		)
	)
	(label "PCIe_JTAG.JTDO"
		(at 325.12 149.86 180)
		(effects
			(font
				(size 1.27 1.27)
			)
			(justify right bottom)
		)
	)
	(label "PCIe_JTAG.JTDI"
		(at 325.12 144.78 180)
		(effects
			(font
				(size 1.27 1.27)
			)
			(justify right bottom)
		)
	)
	(label "PCIe_{x4}_AC.TX3+"
		(at 195.58 148.59 180)
		(effects
			(font
				(size 1.27 1.27)
			)
			(justify right bottom)
		)
	)
	(label "GEN_CLK+"
		(at 210.82 255.27 180)
		(effects
			(font
				(size 1.27 1.27)
			)
			(justify right bottom)
		)
	)
	(label "PCIe_{x4}_AC.TX2+"
		(at 195.58 133.35 180)
		(effects
			(font
				(size 1.27 1.27)
			)
			(justify right bottom)
		)
	)
	(label "REFCLK.+"
		(at 156.21 95.25 180)
		(effects
			(font
				(size 1.27 1.27)
			)
			(justify right bottom)
		)
	)
	(label "RBIAS"
		(at 234.95 217.17 0)
		(effects
			(font
				(size 1.27 1.27)
			)
			(justify left bottom)
		)
	)
	(label "PCIe_JTAG.~{JRST}"
		(at 325.12 139.7 180)
		(effects
			(font
				(size 1.27 1.27)
			)
			(justify right bottom)
		)
	)
	(label "PCIe_{x4}.TX2+"
		(at 156.21 133.35 180)
		(effects
			(font
				(size 1.27 1.27)
			)
			(justify right bottom)
		)
	)
	(label "PCIe_JTAG.JTDO"
		(at 290.83 97.79 180)
		(effects
			(font
				(size 1.27 1.27)
			)
			(justify right bottom)
		)
	)
	(label "PCIe_{x4}.RX3+"
		(at 156.21 156.21 180)
		(effects
			(font
				(size 1.27 1.27)
			)
			(justify right bottom)
		)
	)
	(label "PCIe_{x4}.RX1-"
		(at 156.21 128.27 180)
		(effects
			(font
				(size 1.27 1.27)
			)
			(justify right bottom)
		)
	)
	(label "PCIe_{x4}.RX2+"
		(at 156.21 140.97 180)
		(effects
			(font
				(size 1.27 1.27)
			)
			(justify right bottom)
		)
	)
	(label "CLK-"
		(at 180.34 97.79 180)
		(effects
			(font
				(size 1.27 1.27)
			)
			(justify right bottom)
		)
	)
	(label "PCIe_{x4}.RX0-"
		(at 156.21 113.03 180)
		(effects
			(font
				(size 1.27 1.27)
			)
			(justify right bottom)
		)
	)
	(label "PCIe_JTAG.JTCK"
		(at 255.27 147.32 0)
		(effects
			(font
				(size 1.27 1.27)
			)
			(justify left bottom)
		)
	)
	(label "PCIe_{x4}.TX0-"
		(at 156.21 105.41 180)
		(effects
			(font
				(size 1.27 1.27)
			)
			(justify right bottom)
		)
	)
	(label "PCIe_{x4}.RX2-"
		(at 156.21 143.51 180)
		(effects
			(font
				(size 1.27 1.27)
			)
			(justify right bottom)
		)
	)
	(label "PCIe_{x4}_AC.TX3-"
		(at 195.58 151.13 180)
		(effects
			(font
				(size 1.27 1.27)
			)
			(justify right bottom)
		)
	)
	(label "PCIe_{x4}_AC.TX1+"
		(at 195.58 118.11 180)
		(effects
			(font
				(size 1.27 1.27)
			)
			(justify right bottom)
		)
	)
	(label "GEN_F_CLK-"
		(at 245.11 257.81 180)
		(effects
			(font
				(size 1.27 1.27)
			)
			(justify right bottom)
		)
	)
	(label "PCIe_{x4}_AC.TX1-"
		(at 195.58 120.65 180)
		(effects
			(font
				(size 1.27 1.27)
			)
			(justify right bottom)
		)
	)
	(label "CLK+"
		(at 180.34 95.25 180)
		(effects
			(font
				(size 1.27 1.27)
			)
			(justify right bottom)
		)
	)
	(hierarchical_label "REFCLK{CLK}"
		(shape input)
		(at 135.89 105.41 180)
		(effects
			(font
				(size 1.27 1.27)
			)
			(justify right)
		)
	)
	(hierarchical_label "~{PE_RST}"
		(shape input)
		(at 156.21 87.63 180)
		(effects
			(font
				(size 1.27 1.27)
			)
			(justify right)
		)
	)
	(hierarchical_label "PCIe_{x4}{PCIe}"
		(shape bidirectional)
		(at 135.89 166.37 180)
		(effects
			(font
				(size 1.27 1.27)
			)
			(justify right)
		)
	)
	(hierarchical_label "~{PE_WAKE}"
		(shape output)
		(at 156.21 90.17 180)
		(effects
			(font
				(size 1.27 1.27)
			)
			(justify right)
		)
	)
	(rule_area
		(polyline
			(pts
				(xy 139.7 92.71) (xy 196.85 92.71) (xy 196.85 160.02) (xy 139.7 160.02)
			)
			(stroke
				(width 0)
				(type dash)
			)
			(fill
				(type none)
			)
		)
	)
	(rule_area
		(polyline
			(pts
				(xy 200.66 251.46) (xy 245.11 251.46) (xy 245.11 259.08) (xy 200.66 259.08)
			)
			(stroke
				(width 0)
				(type dash)
			)
			(fill
				(type none)
			)
		)
	)
	(netclass_flag ""
		(length 2.54)
		(shape round)
		(at 245.11 251.46 0)
		(fields_autoplaced yes)
		(effects
			(font
				(size 1.27 1.27)
			)
			(justify left bottom)
		)
		(property "Netclass" "85Ohm-diff_PCIe"
			(at 244.4115 248.92 0)
			(effects
				(font
					(size 1.27 1.27)
				)
				(justify right)
			)
		)
		(property "Component Class" ""
			(at 21.59 198.12 0)
			(effects
				(font
					(size 1.27 1.27)
					(italic yes)
				)
				(justify right)
			)
		)
	)
	(netclass_flag ""
		(length 2.54)
		(shape round)
		(at 139.7 92.71 0)
		(fields_autoplaced yes)
		(effects
			(font
				(size 1.27 1.27)
			)
			(justify left bottom)
		)
		(property "Netclass" "85Ohm-diff_PCIe"
			(at 139.0015 90.17 0)
			(effects
				(font
					(size 1.27 1.27)
				)
				(justify right)
			)
		)
		(property "Component Class" ""
			(at -83.82 39.37 0)
			(effects
				(font
					(size 1.27 1.27)
					(italic yes)
				)
				(justify right)
			)
		)
	)
	(symbol
		(lib_id "antmicroResistors0402:R_8k2_0402")
		(at 254 82.55 90)
		(unit 1)
		(exclude_from_sim no)
		(in_bom yes)
		(on_board yes)
		(dnp no)
		(property "Reference" "R53"
			(at 255.524 78.74 90)
			(effects
				(font
					(size 1.27 1.27)
					(thickness 0.15)
				)
				(justify right)
			)
		)
		(property "Value" "R_8k2_0402"
			(at 266.7 62.23 0)
			(effects
				(font
					(size 1.27 1.27)
					(thickness 0.15)
				)
				(justify left bottom)
				(hide yes)
			)
		)
		(property "Footprint" "antmicro-footprints:R_0402_1005Metric"
			(at 269.24 62.23 0)
			(effects
				(font
					(size 1.27 1.27)
					(thickness 0.15)
				)
				(justify left bottom)
				(hide yes)
			)
		)
		(property "Datasheet" "https://www.bourns.com/docs/product-datasheets/cr.pdf"
			(at 271.78 62.23 0)
			(effects
				(font
					(size 1.27 1.27)
					(thickness 0.15)
				)
				(justify left bottom)
				(hide yes)
			)
		)
		(property "Description" "SMD Chip Resistor"
			(at 254 82.55 0)
			(effects
				(font
					(size 1.27 1.27)
				)
				(hide yes)
			)
		)
		(property "MPN" "CR0402-FX-8201GLF"
			(at 274.32 62.23 0)
			(effects
				(font
					(size 1.27 1.27)
					(thickness 0.15)
				)
				(justify left bottom)
				(hide yes)
			)
		)
		(property "Manufacturer" "Bourns"
			(at 276.86 62.23 0)
			(effects
				(font
					(size 1.27 1.27)
					(thickness 0.15)
				)
				(justify left bottom)
				(hide yes)
			)
		)
		(property "License" "Apache-2.0"
			(at 279.4 62.23 0)
			(effects
				(font
					(size 1.27 1.27)
					(thickness 0.15)
				)
				(justify left bottom)
				(hide yes)
			)
		)
		(property "Author" "Antmicro"
			(at 281.94 62.23 0)
			(effects
				(font
					(size 1.27 1.27)
					(thickness 0.15)
				)
				(justify left bottom)
				(hide yes)
			)
		)
		(property "Val" "8k2"
			(at 255.524 81.28 90)
			(effects
				(font
					(size 1.27 1.27)
					(thickness 0.15)
				)
				(justify right)
			)
		)
		(property "Tolerance" "1%"
			(at 264.16 62.23 0)
			(effects
				(font
					(size 1.27 1.27)
				)
				(justify left bottom)
				(hide yes)
			)
		)
		(pin "1"
		)
		(pin "2"
		)
		(instances
			(project "OCuLink to 10GbE adapter"
				(path ""
					(reference "R53")
					(unit 1)
				)
			)
		)
	)
	(symbol
		(lib_id "antmicroCapacitors0402:C_220n_16V_0402")
		(at 168.91 148.59 0)
		(unit 1)
		(exclude_from_sim no)
		(in_bom yes)
		(on_board yes)
		(dnp no)
		(property "Reference" "C196"
			(at 170.18 147.32 0)
			(effects
				(font
					(size 1.27 1.27)
					(thickness 0.15)
				)
				(justify right)
			)
		)
		(property "Value" "C_220n_16V_0402"
			(at 189.23 158.75 0)
			(effects
				(font
					(size 1.27 1.27)
					(thickness 0.15)
				)
				(justify left bottom)
				(hide yes)
			)
		)
		(property "Footprint" "antmicro-footprints:C_0402_1005Metric"
			(at 189.23 161.29 0)
			(effects
				(font
					(size 1.27 1.27)
					(thickness 0.15)
				)
				(justify left bottom)
				(hide yes)
			)
		)
		(property "Datasheet" "https://www.murata.com/products/productdetail?partno=GRM155R71C224KA12%23"
			(at 189.23 163.83 0)
			(effects
				(font
					(size 1.27 1.27)
					(thickness 0.15)
				)
				(justify left bottom)
				(hide yes)
			)
		)
		(property "Description" "SMD Multilayer Ceramic Capacitor, 0.22 µF, 16 V, 0402 [1005 Metric], ± 10%, X7R, GRM Series"
			(at 168.91 148.59 0)
			(effects
				(font
					(size 1.27 1.27)
				)
				(hide yes)
			)
		)
		(property "MPN" "GRM155R71C224KA12D"
			(at 189.23 166.37 0)
			(effects
				(font
					(size 1.27 1.27)
					(thickness 0.15)
				)
				(justify left bottom)
				(hide yes)
			)
		)
		(property "Manufacturer" "Murata"
			(at 189.23 168.91 0)
			(effects
				(font
					(size 1.27 1.27)
					(thickness 0.15)
				)
				(justify left bottom)
				(hide yes)
			)
		)
		(property "License" "Apache-2.0"
			(at 189.23 171.45 0)
			(effects
				(font
					(size 1.27 1.27)
					(thickness 0.15)
				)
				(justify left bottom)
				(hide yes)
			)
		)
		(property "Author" "Antmicro"
			(at 189.23 173.99 0)
			(effects
				(font
					(size 1.27 1.27)
					(thickness 0.15)
				)
				(justify left bottom)
				(hide yes)
			)
		)
		(property "Val" "220n"
			(at 172.72 147.32 0)
			(effects
				(font
					(size 1.27 1.27)
					(thickness 0.15)
				)
				(justify left)
			)
		)
		(property "Voltage" "16V"
			(at 189.23 176.53 0)
			(effects
				(font
					(size 1.27 1.27)
				)
				(justify left bottom)
				(hide yes)
			)
		)
		(property "Dielectric" "X7R"
			(at 189.23 179.07 0)
			(effects
				(font
					(size 1.27 1.27)
				)
				(justify left bottom)
				(hide yes)
			)
		)
		(pin "2"
		)
		(pin "1"
		)
		(instances
			(project "OCuLink to 10GbE adapter"
				(path ""
					(reference "C196")
					(unit 1)
				)
			)
		)
	)
	(symbol
		(lib_id "antmicroResistors0402:R_0R_0402")
		(at 162.56 95.25 0)
		(unit 1)
		(exclude_from_sim no)
		(in_bom yes)
		(on_board yes)
		(dnp no)
		(property "Reference" "R95"
			(at 159.512 94.234 0)
			(effects
				(font
					(size 1.27 1.27)
					(thickness 0.15)
				)
			)
		)
		(property "Value" "R_0R_0402"
			(at 182.88 107.95 0)
			(effects
				(font
					(size 1.27 1.27)
					(thickness 0.15)
				)
				(justify left bottom)
				(hide yes)
			)
		)
		(property "Footprint" "antmicro-footprints:R_0402_1005Metric"
			(at 182.88 110.49 0)
			(effects
				(font
					(size 1.27 1.27)
					(thickness 0.15)
				)
				(justify left bottom)
				(hide yes)
			)
		)
		(property "Datasheet" "https://industrial.panasonic.com/cdbs/www-data/pdf/RDA0000/AOA0000C301.pdf"
			(at 182.88 113.03 0)
			(effects
				(font
					(size 1.27 1.27)
					(thickness 0.15)
				)
				(justify left bottom)
				(hide yes)
			)
		)
		(property "Description" "SMD Chip Resistor, Jumper, 0 ohm, 100 mW, 0402 [1005 Metric], Thick Film, General Purpose"
			(at 182.88 128.27 0)
			(effects
				(font
					(size 1.27 1.27)
				)
				(justify left bottom)
				(hide yes)
			)
		)
		(property "MPN" "ERJ2GE0R00X"
			(at 182.88 115.57 0)
			(effects
				(font
					(size 1.27 1.27)
					(thickness 0.15)
				)
				(justify left bottom)
				(hide yes)
			)
		)
		(property "Manufacturer" "Panasonic"
			(at 182.88 118.11 0)
			(effects
				(font
					(size 1.27 1.27)
					(thickness 0.15)
				)
				(justify left bottom)
				(hide yes)
			)
		)
		(property "License" "Apache-2.0"
			(at 182.88 120.65 0)
			(effects
				(font
					(size 1.27 1.27)
					(thickness 0.15)
				)
				(justify left bottom)
				(hide yes)
			)
		)
		(property "Author" "Antmicro"
			(at 182.88 123.19 0)
			(effects
				(font
					(size 1.27 1.27)
					(thickness 0.15)
				)
				(justify left bottom)
				(hide yes)
			)
		)
		(property "Val" "0R"
			(at 168.91 94.234 0)
			(effects
				(font
					(size 1.27 1.27)
					(thickness 0.15)
				)
			)
		)
		(property "Tolerance" "~"
			(at 182.88 105.41 0)
			(effects
				(font
					(size 1.27 1.27)
				)
				(justify left bottom)
				(hide yes)
			)
		)
		(property "Current" "1A"
			(at 182.88 125.73 0)
			(effects
				(font
					(size 1.27 1.27)
					(thickness 0.15)
				)
				(justify left bottom)
				(hide yes)
			)
		)
		(pin "2"
		)
		(pin "1"
		)
		(instances
			(project "oculink-to-10gbe-adapter"
				(path ""
					(reference "R95")
					(unit 1)
				)
			)
		)
	)
	(symbol
		(lib_id "antmicroResistors0402:R_0R_0402")
		(at 250.19 255.27 0)
		(unit 1)
		(exclude_from_sim no)
		(in_bom no)
		(on_board yes)
		(dnp yes)
		(property "Reference" "R120"
			(at 247.142 254.254 0)
			(effects
				(font
					(size 1.27 1.27)
					(thickness 0.15)
				)
			)
		)
		(property "Value" "R_0R_0402"
			(at 270.51 267.97 0)
			(effects
				(font
					(size 1.27 1.27)
					(thickness 0.15)
				)
				(justify left bottom)
				(hide yes)
			)
		)
		(property "Footprint" "antmicro-footprints:R_0402_1005Metric"
			(at 270.51 270.51 0)
			(effects
				(font
					(size 1.27 1.27)
					(thickness 0.15)
				)
				(justify left bottom)
				(hide yes)
			)
		)
		(property "Datasheet" "https://industrial.panasonic.com/cdbs/www-data/pdf/RDA0000/AOA0000C301.pdf"
			(at 270.51 273.05 0)
			(effects
				(font
					(size 1.27 1.27)
					(thickness 0.15)
				)
				(justify left bottom)
				(hide yes)
			)
		)
		(property "Description" "SMD Chip Resistor, Jumper, 0 ohm, 100 mW, 0402 [1005 Metric], Thick Film, General Purpose"
			(at 270.51 288.29 0)
			(effects
				(font
					(size 1.27 1.27)
				)
				(justify left bottom)
				(hide yes)
			)
		)
		(property "MPN" "ERJ2GE0R00X"
			(at 270.51 275.59 0)
			(effects
				(font
					(size 1.27 1.27)
					(thickness 0.15)
				)
				(justify left bottom)
				(hide yes)
			)
		)
		(property "Manufacturer" "Panasonic"
			(at 270.51 278.13 0)
			(effects
				(font
					(size 1.27 1.27)
					(thickness 0.15)
				)
				(justify left bottom)
				(hide yes)
			)
		)
		(property "License" "Apache-2.0"
			(at 270.51 280.67 0)
			(effects
				(font
					(size 1.27 1.27)
					(thickness 0.15)
				)
				(justify left bottom)
				(hide yes)
			)
		)
		(property "Author" "Antmicro"
			(at 270.51 283.21 0)
			(effects
				(font
					(size 1.27 1.27)
					(thickness 0.15)
				)
				(justify left bottom)
				(hide yes)
			)
		)
		(property "Val" "0R"
			(at 256.54 254.254 0)
			(effects
				(font
					(size 1.27 1.27)
					(thickness 0.15)
				)
			)
		)
		(property "Tolerance" "~"
			(at 270.51 265.43 0)
			(effects
				(font
					(size 1.27 1.27)
				)
				(justify left bottom)
				(hide yes)
			)
		)
		(property "Current" "1A"
			(at 270.51 285.75 0)
			(effects
				(font
					(size 1.27 1.27)
					(thickness 0.15)
				)
				(justify left bottom)
				(hide yes)
			)
		)
		(pin "2"
		)
		(pin "1"
		)
		(instances
			(project ""
				(path ""
					(reference "R120")
					(unit 1)
				)
			)
		)
	)
	(symbol
		(lib_id "antmicropower:+3V3")
		(at 254 72.39 0)
		(unit 1)
		(exclude_from_sim no)
		(in_bom yes)
		(on_board yes)
		(dnp no)
		(property "Reference" "#PWR0245"
			(at 269.24 72.39 0)
			(effects
				(font
					(size 1.27 1.27)
					(thickness 0.15)
				)
				(justify left bottom)
				(hide yes)
			)
		)
		(property "Value" "+3V3"
			(at 254 68.58 0)
			(effects
				(font
					(size 1.27 1.27)
					(thickness 0.15)
				)
			)
		)
		(property "Footprint" ""
			(at 269.24 80.01 0)
			(effects
				(font
					(size 1.27 1.27)
					(thickness 0.15)
				)
				(justify left bottom)
				(hide yes)
			)
		)
		(property "Datasheet" ""
			(at 269.24 82.55 0)
			(effects
				(font
					(size 1.27 1.27)
					(thickness 0.15)
				)
				(justify left bottom)
				(hide yes)
			)
		)
		(property "Description" ""
			(at 254 72.39 0)
			(effects
				(font
					(size 1.27 1.27)
				)
				(hide yes)
			)
		)
		(property "Author" "Antmicro"
			(at 269.24 74.93 0)
			(effects
				(font
					(size 1.27 1.27)
					(thickness 0.15)
				)
				(justify left bottom)
				(hide yes)
			)
		)
		(property "License" "Apache-2.0"
			(at 269.24 77.47 0)
			(effects
				(font
					(size 1.27 1.27)
					(thickness 0.15)
				)
				(justify left bottom)
				(hide yes)
			)
		)
		(pin "1"
		)
		(instances
			(project "OCuLink to 10GbE adapter"
				(path ""
					(reference "#PWR0245")
					(unit 1)
				)
			)
		)
	)
	(symbol
		(lib_id "antmicroResistors0402:R_4k75_0.5%_0402")
		(at 243.84 217.17 0)
		(unit 1)
		(exclude_from_sim no)
		(in_bom yes)
		(on_board yes)
		(dnp no)
		(property "Reference" "R56"
			(at 246.38 212.09 0)
			(effects
				(font
					(size 1.27 1.27)
					(thickness 0.15)
				)
			)
		)
		(property "Value" "R_4k75_0.5%_0402"
			(at 264.16 229.87 0)
			(effects
				(font
					(size 1.27 1.27)
					(thickness 0.15)
				)
				(justify left bottom)
				(hide yes)
			)
		)
		(property "Footprint" "antmicro-footprints:R_0402_1005Metric"
			(at 264.16 232.41 0)
			(effects
				(font
					(size 1.27 1.27)
					(thickness 0.15)
				)
				(justify left bottom)
				(hide yes)
			)
		)
		(property "Datasheet" "https://industrial.panasonic.com/cdbs/www-data/pdf/RDQ0000/ast-ind-151033.pdf"
			(at 264.16 234.95 0)
			(effects
				(font
					(size 1.27 1.27)
					(thickness 0.15)
				)
				(justify left bottom)
				(hide yes)
			)
		)
		(property "Description" "SMD Chip Resistor, 4.75 kohm, ± 0.5%, 100 mW, 0402 [1005 Metric], Thick Film, High Temperature"
			(at 243.84 217.17 0)
			(effects
				(font
					(size 1.27 1.27)
				)
				(hide yes)
			)
		)
		(property "MPN" "ERJ-H2RD4751X"
			(at 264.16 237.49 0)
			(effects
				(font
					(size 1.27 1.27)
					(thickness 0.15)
				)
				(justify left bottom)
				(hide yes)
			)
		)
		(property "Manufacturer" "Panasonic"
			(at 264.16 240.03 0)
			(effects
				(font
					(size 1.27 1.27)
					(thickness 0.15)
				)
				(justify left bottom)
				(hide yes)
			)
		)
		(property "License" "Apache-2.0"
			(at 264.16 242.57 0)
			(effects
				(font
					(size 1.27 1.27)
					(thickness 0.15)
				)
				(justify left bottom)
				(hide yes)
			)
		)
		(property "Author" "Antmicro"
			(at 264.16 245.11 0)
			(effects
				(font
					(size 1.27 1.27)
					(thickness 0.15)
				)
				(justify left bottom)
				(hide yes)
			)
		)
		(property "Val" "4k75"
			(at 246.38 214.63 0)
			(effects
				(font
					(size 1.27 1.27)
					(thickness 0.15)
				)
			)
		)
		(property "Tolerance" "0.5%"
			(at 264.16 227.33 0)
			(effects
				(font
					(size 1.27 1.27)
				)
				(justify left bottom)
				(hide yes)
			)
		)
		(pin "1"
		)
		(pin "2"
		)
		(instances
			(project "OCuLink to 10GbE adapter"
				(path ""
					(reference "R56")
					(unit 1)
				)
			)
		)
	)
	(symbol
		(lib_id "antmicroCapacitors0402:C_220n_16V_0402")
		(at 168.91 133.35 0)
		(unit 1)
		(exclude_from_sim no)
		(in_bom yes)
		(on_board yes)
		(dnp no)
		(property "Reference" "C194"
			(at 170.18 132.08 0)
			(effects
				(font
					(size 1.27 1.27)
					(thickness 0.15)
				)
				(justify right)
			)
		)
		(property "Value" "C_220n_16V_0402"
			(at 189.23 143.51 0)
			(effects
				(font
					(size 1.27 1.27)
					(thickness 0.15)
				)
				(justify left bottom)
				(hide yes)
			)
		)
		(property "Footprint" "antmicro-footprints:C_0402_1005Metric"
			(at 189.23 146.05 0)
			(effects
				(font
					(size 1.27 1.27)
					(thickness 0.15)
				)
				(justify left bottom)
				(hide yes)
			)
		)
		(property "Datasheet" "https://www.murata.com/products/productdetail?partno=GRM155R71C224KA12%23"
			(at 189.23 148.59 0)
			(effects
				(font
					(size 1.27 1.27)
					(thickness 0.15)
				)
				(justify left bottom)
				(hide yes)
			)
		)
		(property "Description" "SMD Multilayer Ceramic Capacitor, 0.22 µF, 16 V, 0402 [1005 Metric], ± 10%, X7R, GRM Series"
			(at 168.91 133.35 0)
			(effects
				(font
					(size 1.27 1.27)
				)
				(hide yes)
			)
		)
		(property "MPN" "GRM155R71C224KA12D"
			(at 189.23 151.13 0)
			(effects
				(font
					(size 1.27 1.27)
					(thickness 0.15)
				)
				(justify left bottom)
				(hide yes)
			)
		)
		(property "Manufacturer" "Murata"
			(at 189.23 153.67 0)
			(effects
				(font
					(size 1.27 1.27)
					(thickness 0.15)
				)
				(justify left bottom)
				(hide yes)
			)
		)
		(property "License" "Apache-2.0"
			(at 189.23 156.21 0)
			(effects
				(font
					(size 1.27 1.27)
					(thickness 0.15)
				)
				(justify left bottom)
				(hide yes)
			)
		)
		(property "Author" "Antmicro"
			(at 189.23 158.75 0)
			(effects
				(font
					(size 1.27 1.27)
					(thickness 0.15)
				)
				(justify left bottom)
				(hide yes)
			)
		)
		(property "Val" "220n"
			(at 172.72 132.08 0)
			(effects
				(font
					(size 1.27 1.27)
					(thickness 0.15)
				)
				(justify left)
			)
		)
		(property "Voltage" "16V"
			(at 189.23 161.29 0)
			(effects
				(font
					(size 1.27 1.27)
				)
				(justify left bottom)
				(hide yes)
			)
		)
		(property "Dielectric" "X7R"
			(at 189.23 163.83 0)
			(effects
				(font
					(size 1.27 1.27)
				)
				(justify left bottom)
				(hide yes)
			)
		)
		(pin "2"
		)
		(pin "1"
		)
		(instances
			(project "OCuLink to 10GbE adapter"
				(path ""
					(reference "C194")
					(unit 1)
				)
			)
		)
	)
	(symbol
		(lib_id "antmicroCapacitors0402:C_220n_16V_0402")
		(at 160.02 135.89 0)
		(unit 1)
		(exclude_from_sim no)
		(in_bom yes)
		(on_board yes)
		(dnp no)
		(property "Reference" "C195"
			(at 161.29 134.62 0)
			(effects
				(font
					(size 1.27 1.27)
					(thickness 0.15)
				)
				(justify right)
			)
		)
		(property "Value" "C_220n_16V_0402"
			(at 180.34 146.05 0)
			(effects
				(font
					(size 1.27 1.27)
					(thickness 0.15)
				)
				(justify left bottom)
				(hide yes)
			)
		)
		(property "Footprint" "antmicro-footprints:C_0402_1005Metric"
			(at 180.34 148.59 0)
			(effects
				(font
					(size 1.27 1.27)
					(thickness 0.15)
				)
				(justify left bottom)
				(hide yes)
			)
		)
		(property "Datasheet" "https://www.murata.com/products/productdetail?partno=GRM155R71C224KA12%23"
			(at 180.34 151.13 0)
			(effects
				(font
					(size 1.27 1.27)
					(thickness 0.15)
				)
				(justify left bottom)
				(hide yes)
			)
		)
		(property "Description" "SMD Multilayer Ceramic Capacitor, 0.22 µF, 16 V, 0402 [1005 Metric], ± 10%, X7R, GRM Series"
			(at 160.02 135.89 0)
			(effects
				(font
					(size 1.27 1.27)
				)
				(hide yes)
			)
		)
		(property "MPN" "GRM155R71C224KA12D"
			(at 180.34 153.67 0)
			(effects
				(font
					(size 1.27 1.27)
					(thickness 0.15)
				)
				(justify left bottom)
				(hide yes)
			)
		)
		(property "Manufacturer" "Murata"
			(at 180.34 156.21 0)
			(effects
				(font
					(size 1.27 1.27)
					(thickness 0.15)
				)
				(justify left bottom)
				(hide yes)
			)
		)
		(property "License" "Apache-2.0"
			(at 180.34 158.75 0)
			(effects
				(font
					(size 1.27 1.27)
					(thickness 0.15)
				)
				(justify left bottom)
				(hide yes)
			)
		)
		(property "Author" "Antmicro"
			(at 180.34 161.29 0)
			(effects
				(font
					(size 1.27 1.27)
					(thickness 0.15)
				)
				(justify left bottom)
				(hide yes)
			)
		)
		(property "Val" "220n"
			(at 163.83 134.62 0)
			(effects
				(font
					(size 1.27 1.27)
					(thickness 0.15)
				)
				(justify left)
			)
		)
		(property "Voltage" "16V"
			(at 180.34 163.83 0)
			(effects
				(font
					(size 1.27 1.27)
				)
				(justify left bottom)
				(hide yes)
			)
		)
		(property "Dielectric" "X7R"
			(at 180.34 166.37 0)
			(effects
				(font
					(size 1.27 1.27)
				)
				(justify left bottom)
				(hide yes)
			)
		)
		(pin "2"
		)
		(pin "1"
		)
		(instances
			(project "OCuLink to 10GbE adapter"
				(path ""
					(reference "C195")
					(unit 1)
				)
			)
		)
	)
	(symbol
		(lib_id "antmicroResistors0402:R_8k2_0402")
		(at 245.11 82.55 90)
		(unit 1)
		(exclude_from_sim no)
		(in_bom yes)
		(on_board yes)
		(dnp no)
		(property "Reference" "R52"
			(at 246.634 78.74 90)
			(effects
				(font
					(size 1.27 1.27)
					(thickness 0.15)
				)
				(justify right)
			)
		)
		(property "Value" "R_8k2_0402"
			(at 257.81 62.23 0)
			(effects
				(font
					(size 1.27 1.27)
					(thickness 0.15)
				)
				(justify left bottom)
				(hide yes)
			)
		)
		(property "Footprint" "antmicro-footprints:R_0402_1005Metric"
			(at 260.35 62.23 0)
			(effects
				(font
					(size 1.27 1.27)
					(thickness 0.15)
				)
				(justify left bottom)
				(hide yes)
			)
		)
		(property "Datasheet" "https://www.bourns.com/docs/product-datasheets/cr.pdf"
			(at 262.89 62.23 0)
			(effects
				(font
					(size 1.27 1.27)
					(thickness 0.15)
				)
				(justify left bottom)
				(hide yes)
			)
		)
		(property "Description" "SMD Chip Resistor"
			(at 245.11 82.55 0)
			(effects
				(font
					(size 1.27 1.27)
				)
				(hide yes)
			)
		)
		(property "MPN" "CR0402-FX-8201GLF"
			(at 265.43 62.23 0)
			(effects
				(font
					(size 1.27 1.27)
					(thickness 0.15)
				)
				(justify left bottom)
				(hide yes)
			)
		)
		(property "Manufacturer" "Bourns"
			(at 267.97 62.23 0)
			(effects
				(font
					(size 1.27 1.27)
					(thickness 0.15)
				)
				(justify left bottom)
				(hide yes)
			)
		)
		(property "License" "Apache-2.0"
			(at 270.51 62.23 0)
			(effects
				(font
					(size 1.27 1.27)
					(thickness 0.15)
				)
				(justify left bottom)
				(hide yes)
			)
		)
		(property "Author" "Antmicro"
			(at 273.05 62.23 0)
			(effects
				(font
					(size 1.27 1.27)
					(thickness 0.15)
				)
				(justify left bottom)
				(hide yes)
			)
		)
		(property "Val" "8k2"
			(at 246.634 81.28 90)
			(effects
				(font
					(size 1.27 1.27)
					(thickness 0.15)
				)
				(justify right)
			)
		)
		(property "Tolerance" "1%"
			(at 255.27 62.23 0)
			(effects
				(font
					(size 1.27 1.27)
				)
				(justify left bottom)
				(hide yes)
			)
		)
		(pin "1"
		)
		(pin "2"
		)
		(instances
			(project "OCuLink to 10GbE adapter"
				(path ""
					(reference "R52")
					(unit 1)
				)
			)
		)
	)
	(symbol
		(lib_id "antmicroCapacitors0402:C_220n_16V_0402")
		(at 160.02 105.41 0)
		(unit 1)
		(exclude_from_sim no)
		(in_bom yes)
		(on_board yes)
		(dnp no)
		(property "Reference" "C191"
			(at 161.29 104.14 0)
			(effects
				(font
					(size 1.27 1.27)
					(thickness 0.15)
				)
				(justify right)
			)
		)
		(property "Value" "C_220n_16V_0402"
			(at 180.34 115.57 0)
			(effects
				(font
					(size 1.27 1.27)
					(thickness 0.15)
				)
				(justify left bottom)
				(hide yes)
			)
		)
		(property "Footprint" "antmicro-footprints:C_0402_1005Metric"
			(at 180.34 118.11 0)
			(effects
				(font
					(size 1.27 1.27)
					(thickness 0.15)
				)
				(justify left bottom)
				(hide yes)
			)
		)
		(property "Datasheet" "https://www.murata.com/products/productdetail?partno=GRM155R71C224KA12%23"
			(at 180.34 120.65 0)
			(effects
				(font
					(size 1.27 1.27)
					(thickness 0.15)
				)
				(justify left bottom)
				(hide yes)
			)
		)
		(property "Description" "SMD Multilayer Ceramic Capacitor, 0.22 µF, 16 V, 0402 [1005 Metric], ± 10%, X7R, GRM Series"
			(at 160.02 105.41 0)
			(effects
				(font
					(size 1.27 1.27)
				)
				(hide yes)
			)
		)
		(property "MPN" "GRM155R71C224KA12D"
			(at 180.34 123.19 0)
			(effects
				(font
					(size 1.27 1.27)
					(thickness 0.15)
				)
				(justify left bottom)
				(hide yes)
			)
		)
		(property "Manufacturer" "Murata"
			(at 180.34 125.73 0)
			(effects
				(font
					(size 1.27 1.27)
					(thickness 0.15)
				)
				(justify left bottom)
				(hide yes)
			)
		)
		(property "License" "Apache-2.0"
			(at 180.34 128.27 0)
			(effects
				(font
					(size 1.27 1.27)
					(thickness 0.15)
				)
				(justify left bottom)
				(hide yes)
			)
		)
		(property "Author" "Antmicro"
			(at 180.34 130.81 0)
			(effects
				(font
					(size 1.27 1.27)
					(thickness 0.15)
				)
				(justify left bottom)
				(hide yes)
			)
		)
		(property "Val" "220n"
			(at 163.83 104.14 0)
			(effects
				(font
					(size 1.27 1.27)
					(thickness 0.15)
				)
				(justify left)
			)
		)
		(property "Voltage" "16V"
			(at 180.34 133.35 0)
			(effects
				(font
					(size 1.27 1.27)
				)
				(justify left bottom)
				(hide yes)
			)
		)
		(property "Dielectric" "X7R"
			(at 180.34 135.89 0)
			(effects
				(font
					(size 1.27 1.27)
				)
				(justify left bottom)
				(hide yes)
			)
		)
		(pin "2"
		)
		(pin "1"
		)
		(instances
			(project "OCuLink to 10GbE adapter"
				(path ""
					(reference "C191")
					(unit 1)
				)
			)
		)
	)
	(symbol
		(lib_id "antmicropower:GND")
		(at 163.83 262.89 0)
		(mirror y)
		(unit 1)
		(exclude_from_sim no)
		(in_bom yes)
		(on_board yes)
		(dnp no)
		(property "Reference" "#PWR0286"
			(at 163.83 269.24 0)
			(effects
				(font
					(size 1.27 1.27)
				)
				(justify left bottom)
				(hide yes)
			)
		)
		(property "Value" "GND"
			(at 163.83 266.7 0)
			(effects
				(font
					(size 1.27 1.27)
				)
			)
		)
		(property "Footprint" ""
			(at 163.83 262.89 0)
			(effects
				(font
					(size 1.27 1.27)
				)
				(justify left bottom)
				(hide yes)
			)
		)
		(property "Datasheet" ""
			(at 163.83 262.89 0)
			(effects
				(font
					(size 1.27 1.27)
				)
				(justify left bottom)
				(hide yes)
			)
		)
		(property "Description" ""
			(at 163.83 262.89 0)
			(effects
				(font
					(size 1.27 1.27)
				)
				(hide yes)
			)
		)
		(property "Author" "Antmicro"
			(at 154.94 270.51 0)
			(effects
				(font
					(size 1.27 1.27)
					(thickness 0.15)
				)
				(justify left bottom)
				(hide yes)
			)
		)
		(property "License" "Apache-2.0"
			(at 154.94 273.05 0)
			(effects
				(font
					(size 1.27 1.27)
					(thickness 0.15)
				)
				(justify left bottom)
				(hide yes)
			)
		)
		(pin "1"
		)
		(instances
			(project "oculink-to-10gbe-adapter"
				(path ""
					(reference "#PWR0286")
					(unit 1)
				)
			)
		)
	)
	(symbol
		(lib_id "antmicropower:GND")
		(at 232.41 265.43 0)
		(unit 1)
		(exclude_from_sim no)
		(in_bom yes)
		(on_board yes)
		(dnp no)
		(property "Reference" "#PWR0288"
			(at 241.3 267.97 0)
			(effects
				(font
					(size 1.27 1.27)
					(thickness 0.15)
				)
				(justify left bottom)
				(hide yes)
			)
		)
		(property "Value" "GND"
			(at 232.41 269.24 0)
			(effects
				(font
					(size 1.27 1.27)
					(thickness 0.15)
				)
			)
		)
		(property "Footprint" ""
			(at 241.3 273.05 0)
			(effects
				(font
					(size 1.27 1.27)
					(thickness 0.15)
				)
				(justify left bottom)
				(hide yes)
			)
		)
		(property "Datasheet" ""
			(at 241.3 278.13 0)
			(effects
				(font
					(size 1.27 1.27)
					(thickness 0.15)
				)
				(justify left bottom)
				(hide yes)
			)
		)
		(property "Description" ""
			(at 232.41 265.43 0)
			(effects
				(font
					(size 1.27 1.27)
				)
				(hide yes)
			)
		)
		(property "Author" "Antmicro"
			(at 241.3 273.05 0)
			(effects
				(font
					(size 1.27 1.27)
					(thickness 0.15)
				)
				(justify left bottom)
				(hide yes)
			)
		)
		(property "License" "Apache-2.0"
			(at 241.3 275.59 0)
			(effects
				(font
					(size 1.27 1.27)
					(thickness 0.15)
				)
				(justify left bottom)
				(hide yes)
			)
		)
		(pin "1"
		)
		(instances
			(project "oculink-to-10gbe-adapter"
				(path ""
					(reference "#PWR0288")
					(unit 1)
				)
			)
		)
	)
	(symbol
		(lib_id "antmicroOscillators:Oscillator_100MHz_NX324")
		(at 181.61 255.27 0)
		(unit 1)
		(exclude_from_sim no)
		(in_bom no)
		(on_board yes)
		(dnp yes)
		(fields_autoplaced yes)
		(property "Reference" "Y3"
			(at 191.135 245.11 0)
			(effects
				(font
					(size 1.27 1.27)
					(thickness 0.15)
				)
			)
		)
		(property "Value" "Oscillator_100MHz_NX324"
			(at 210.82 267.335 0)
			(effects
				(font
					(size 1.27 1.27)
					(thickness 0.15)
				)
				(justify left bottom)
				(hide yes)
			)
		)
		(property "Footprint" "antmicro-footprints:Oscillator_SMD_Abracon_AX3_3.2x2.5x1mm"
			(at 210.82 269.875 0)
			(effects
				(font
					(size 1.27 1.27)
					(thickness 0.15)
				)
				(justify left bottom)
				(hide yes)
			)
		)
		(property "Datasheet" "https://www.diodes.com/assets/Datasheets/NX324.pdf"
			(at 210.82 272.415 0)
			(effects
				(font
					(size 1.27 1.27)
					(thickness 0.15)
				)
				(justify left bottom)
				(hide yes)
			)
		)
		(property "Description" "100 MHz XO (Standard) HCSL Oscillator 3.3V Enable/Disable 6-SMD, No Lead"
			(at 210.82 280.035 0)
			(effects
				(font
					(size 1.27 1.27)
				)
				(justify left bottom)
				(hide yes)
			)
		)
		(property "Manufacturer" "Diodes Incorporated"
			(at 210.82 259.715 0)
			(effects
				(font
					(size 1.27 1.27)
					(thickness 0.15)
				)
				(justify left bottom)
				(hide yes)
			)
		)
		(property "MPN" "NX3241E0100.000000"
			(at 191.135 247.65 0)
			(effects
				(font
					(size 1.27 1.27)
					(thickness 0.15)
				)
			)
		)
		(property "Val" "100 MHz"
			(at 191.135 250.19 0)
			(effects
				(font
					(size 1.27 1.27)
					(thickness 0.15)
				)
			)
		)
		(property "Author" "Antmicro"
			(at 210.82 274.955 0)
			(effects
				(font
					(size 1.27 1.27)
					(thickness 0.15)
				)
				(justify left bottom)
				(hide yes)
			)
		)
		(property "License" "Apache-2.0"
			(at 210.82 277.495 0)
			(effects
				(font
					(size 1.27 1.27)
					(thickness 0.15)
				)
				(justify left bottom)
				(hide yes)
			)
		)
		(pin "3"
		)
		(pin "4"
		)
		(pin "6"
		)
		(pin "5"
		)
		(pin "1"
		)
		(pin "2"
		)
		(instances
			(project "oculink-to-10gbe-adapter"
				(path ""
					(reference "Y3")
					(unit 1)
				)
			)
		)
	)
	(symbol
		(lib_id "antmicroResistors0402:R_8k2_0402")
		(at 271.78 106.68 90)
		(unit 1)
		(exclude_from_sim no)
		(in_bom yes)
		(on_board yes)
		(dnp no)
		(property "Reference" "R55"
			(at 273.304 102.87 90)
			(effects
				(font
					(size 1.27 1.27)
					(thickness 0.15)
				)
				(justify right)
			)
		)
		(property "Value" "R_8k2_0402"
			(at 284.48 86.36 0)
			(effects
				(font
					(size 1.27 1.27)
					(thickness 0.15)
				)
				(justify left bottom)
				(hide yes)
			)
		)
		(property "Footprint" "antmicro-footprints:R_0402_1005Metric"
			(at 287.02 86.36 0)
			(effects
				(font
					(size 1.27 1.27)
					(thickness 0.15)
				)
				(justify left bottom)
				(hide yes)
			)
		)
		(property "Datasheet" "https://www.bourns.com/docs/product-datasheets/cr.pdf"
			(at 289.56 86.36 0)
			(effects
				(font
					(size 1.27 1.27)
					(thickness 0.15)
				)
				(justify left bottom)
				(hide yes)
			)
		)
		(property "Description" "SMD Chip Resistor"
			(at 271.78 106.68 0)
			(effects
				(font
					(size 1.27 1.27)
				)
				(hide yes)
			)
		)
		(property "MPN" "CR0402-FX-8201GLF"
			(at 292.1 86.36 0)
			(effects
				(font
					(size 1.27 1.27)
					(thickness 0.15)
				)
				(justify left bottom)
				(hide yes)
			)
		)
		(property "Manufacturer" "Bourns"
			(at 294.64 86.36 0)
			(effects
				(font
					(size 1.27 1.27)
					(thickness 0.15)
				)
				(justify left bottom)
				(hide yes)
			)
		)
		(property "License" "Apache-2.0"
			(at 297.18 86.36 0)
			(effects
				(font
					(size 1.27 1.27)
					(thickness 0.15)
				)
				(justify left bottom)
				(hide yes)
			)
		)
		(property "Author" "Antmicro"
			(at 299.72 86.36 0)
			(effects
				(font
					(size 1.27 1.27)
					(thickness 0.15)
				)
				(justify left bottom)
				(hide yes)
			)
		)
		(property "Val" "8k2"
			(at 273.304 105.41 90)
			(effects
				(font
					(size 1.27 1.27)
					(thickness 0.15)
				)
				(justify right)
			)
		)
		(property "Tolerance" "1%"
			(at 281.94 86.36 0)
			(effects
				(font
					(size 1.27 1.27)
				)
				(justify left bottom)
				(hide yes)
			)
		)
		(pin "1"
		)
		(pin "2"
		)
		(instances
			(project "OCuLink to 10GbE adapter"
				(path ""
					(reference "R55")
					(unit 1)
				)
			)
		)
	)
	(symbol
		(lib_id "antmicropower:GND")
		(at 262.89 109.22 0)
		(unit 1)
		(exclude_from_sim no)
		(in_bom yes)
		(on_board yes)
		(dnp no)
		(property "Reference" "#PWR0246"
			(at 271.78 111.76 0)
			(effects
				(font
					(size 1.27 1.27)
					(thickness 0.15)
				)
				(justify left bottom)
				(hide yes)
			)
		)
		(property "Value" "GND"
			(at 262.89 113.03 0)
			(effects
				(font
					(size 1.27 1.27)
					(thickness 0.15)
				)
			)
		)
		(property "Footprint" ""
			(at 271.78 116.84 0)
			(effects
				(font
					(size 1.27 1.27)
					(thickness 0.15)
				)
				(justify left bottom)
				(hide yes)
			)
		)
		(property "Datasheet" ""
			(at 271.78 121.92 0)
			(effects
				(font
					(size 1.27 1.27)
					(thickness 0.15)
				)
				(justify left bottom)
				(hide yes)
			)
		)
		(property "Description" ""
			(at 262.89 109.22 0)
			(effects
				(font
					(size 1.27 1.27)
				)
				(hide yes)
			)
		)
		(property "Author" "Antmicro"
			(at 271.78 116.84 0)
			(effects
				(font
					(size 1.27 1.27)
					(thickness 0.15)
				)
				(justify left bottom)
				(hide yes)
			)
		)
		(property "License" "Apache-2.0"
			(at 271.78 119.38 0)
			(effects
				(font
					(size 1.27 1.27)
					(thickness 0.15)
				)
				(justify left bottom)
				(hide yes)
			)
		)
		(pin "1"
		)
		(instances
			(project "OCuLink to 10GbE adapter"
				(path ""
					(reference "#PWR0246")
					(unit 1)
				)
			)
		)
	)
	(symbol
		(lib_id "antmicropower:GND")
		(at 224.79 265.43 0)
		(unit 1)
		(exclude_from_sim no)
		(in_bom yes)
		(on_board yes)
		(dnp no)
		(property "Reference" "#PWR0287"
			(at 233.68 267.97 0)
			(effects
				(font
					(size 1.27 1.27)
					(thickness 0.15)
				)
				(justify left bottom)
				(hide yes)
			)
		)
		(property "Value" "GND"
			(at 224.79 269.24 0)
			(effects
				(font
					(size 1.27 1.27)
					(thickness 0.15)
				)
			)
		)
		(property "Footprint" ""
			(at 233.68 273.05 0)
			(effects
				(font
					(size 1.27 1.27)
					(thickness 0.15)
				)
				(justify left bottom)
				(hide yes)
			)
		)
		(property "Datasheet" ""
			(at 233.68 278.13 0)
			(effects
				(font
					(size 1.27 1.27)
					(thickness 0.15)
				)
				(justify left bottom)
				(hide yes)
			)
		)
		(property "Description" ""
			(at 224.79 265.43 0)
			(effects
				(font
					(size 1.27 1.27)
				)
				(hide yes)
			)
		)
		(property "Author" "Antmicro"
			(at 233.68 273.05 0)
			(effects
				(font
					(size 1.27 1.27)
					(thickness 0.15)
				)
				(justify left bottom)
				(hide yes)
			)
		)
		(property "License" "Apache-2.0"
			(at 233.68 275.59 0)
			(effects
				(font
					(size 1.27 1.27)
					(thickness 0.15)
				)
				(justify left bottom)
				(hide yes)
			)
		)
		(pin "1"
		)
		(instances
			(project "oculink-to-10gbe-adapter"
				(path ""
					(reference "#PWR0287")
					(unit 1)
				)
			)
		)
	)
	(symbol
		(lib_id "antmicropower:+3V3")
		(at 163.83 254 0)
		(unit 1)
		(exclude_from_sim no)
		(in_bom yes)
		(on_board yes)
		(dnp no)
		(fields_autoplaced yes)
		(property "Reference" "#PWR0285"
			(at 179.07 254 0)
			(effects
				(font
					(size 1.27 1.27)
					(thickness 0.15)
				)
				(justify left bottom)
				(hide yes)
			)
		)
		(property "Value" "+3V3"
			(at 163.83 248.92 0)
			(effects
				(font
					(size 1.27 1.27)
					(thickness 0.15)
				)
			)
		)
		(property "Footprint" ""
			(at 179.07 261.62 0)
			(effects
				(font
					(size 1.27 1.27)
					(thickness 0.15)
				)
				(justify left bottom)
				(hide yes)
			)
		)
		(property "Datasheet" ""
			(at 179.07 264.16 0)
			(effects
				(font
					(size 1.27 1.27)
					(thickness 0.15)
				)
				(justify left bottom)
				(hide yes)
			)
		)
		(property "Description" ""
			(at 163.83 254 0)
			(effects
				(font
					(size 1.27 1.27)
				)
				(hide yes)
			)
		)
		(property "Author" "Antmicro"
			(at 179.07 256.54 0)
			(effects
				(font
					(size 1.27 1.27)
					(thickness 0.15)
				)
				(justify left bottom)
				(hide yes)
			)
		)
		(property "License" "Apache-2.0"
			(at 179.07 259.08 0)
			(effects
				(font
					(size 1.27 1.27)
					(thickness 0.15)
				)
				(justify left bottom)
				(hide yes)
			)
		)
		(pin "1"
		)
		(instances
			(project "oculink-to-10gbe-adapter"
				(path ""
					(reference "#PWR0285")
					(unit 1)
				)
			)
		)
	)
	(symbol
		(lib_id "antmicroResistors0402:R_0R_0402")
		(at 162.56 97.79 0)
		(unit 1)
		(exclude_from_sim no)
		(in_bom yes)
		(on_board yes)
		(dnp no)
		(property "Reference" "R101"
			(at 159.512 96.52 0)
			(effects
				(font
					(size 1.27 1.27)
					(thickness 0.15)
				)
			)
		)
		(property "Value" "R_0R_0402"
			(at 182.88 110.49 0)
			(effects
				(font
					(size 1.27 1.27)
					(thickness 0.15)
				)
				(justify left bottom)
				(hide yes)
			)
		)
		(property "Footprint" "antmicro-footprints:R_0402_1005Metric"
			(at 182.88 113.03 0)
			(effects
				(font
					(size 1.27 1.27)
					(thickness 0.15)
				)
				(justify left bottom)
				(hide yes)
			)
		)
		(property "Datasheet" "https://industrial.panasonic.com/cdbs/www-data/pdf/RDA0000/AOA0000C301.pdf"
			(at 182.88 115.57 0)
			(effects
				(font
					(size 1.27 1.27)
					(thickness 0.15)
				)
				(justify left bottom)
				(hide yes)
			)
		)
		(property "Description" "SMD Chip Resistor, Jumper, 0 ohm, 100 mW, 0402 [1005 Metric], Thick Film, General Purpose"
			(at 182.88 130.81 0)
			(effects
				(font
					(size 1.27 1.27)
				)
				(justify left bottom)
				(hide yes)
			)
		)
		(property "MPN" "ERJ2GE0R00X"
			(at 182.88 118.11 0)
			(effects
				(font
					(size 1.27 1.27)
					(thickness 0.15)
				)
				(justify left bottom)
				(hide yes)
			)
		)
		(property "Manufacturer" "Panasonic"
			(at 182.88 120.65 0)
			(effects
				(font
					(size 1.27 1.27)
					(thickness 0.15)
				)
				(justify left bottom)
				(hide yes)
			)
		)
		(property "License" "Apache-2.0"
			(at 182.88 123.19 0)
			(effects
				(font
					(size 1.27 1.27)
					(thickness 0.15)
				)
				(justify left bottom)
				(hide yes)
			)
		)
		(property "Author" "Antmicro"
			(at 182.88 125.73 0)
			(effects
				(font
					(size 1.27 1.27)
					(thickness 0.15)
				)
				(justify left bottom)
				(hide yes)
			)
		)
		(property "Val" "0R"
			(at 168.91 96.52 0)
			(effects
				(font
					(size 1.27 1.27)
					(thickness 0.15)
				)
			)
		)
		(property "Tolerance" "~"
			(at 182.88 107.95 0)
			(effects
				(font
					(size 1.27 1.27)
				)
				(justify left bottom)
				(hide yes)
			)
		)
		(property "Current" "1A"
			(at 182.88 128.27 0)
			(effects
				(font
					(size 1.27 1.27)
					(thickness 0.15)
				)
				(justify left bottom)
				(hide yes)
			)
		)
		(pin "2"
		)
		(pin "1"
		)
		(instances
			(project "oculink-to-10gbe-adapter"
				(path ""
					(reference "R101")
					(unit 1)
				)
			)
		)
	)
	(symbol
		(lib_id "antmicroResistors0402:R_8k2_0402")
		(at 262.89 106.68 90)
		(unit 1)
		(exclude_from_sim no)
		(in_bom yes)
		(on_board yes)
		(dnp no)
		(property "Reference" "R54"
			(at 264.414 102.87 90)
			(effects
				(font
					(size 1.27 1.27)
					(thickness 0.15)
				)
				(justify right)
			)
		)
		(property "Value" "R_8k2_0402"
			(at 275.59 86.36 0)
			(effects
				(font
					(size 1.27 1.27)
					(thickness 0.15)
				)
				(justify left bottom)
				(hide yes)
			)
		)
		(property "Footprint" "antmicro-footprints:R_0402_1005Metric"
			(at 278.13 86.36 0)
			(effects
				(font
					(size 1.27 1.27)
					(thickness 0.15)
				)
				(justify left bottom)
				(hide yes)
			)
		)
		(property "Datasheet" "https://www.bourns.com/docs/product-datasheets/cr.pdf"
			(at 280.67 86.36 0)
			(effects
				(font
					(size 1.27 1.27)
					(thickness 0.15)
				)
				(justify left bottom)
				(hide yes)
			)
		)
		(property "Description" "SMD Chip Resistor"
			(at 262.89 106.68 0)
			(effects
				(font
					(size 1.27 1.27)
				)
				(hide yes)
			)
		)
		(property "MPN" "CR0402-FX-8201GLF"
			(at 283.21 86.36 0)
			(effects
				(font
					(size 1.27 1.27)
					(thickness 0.15)
				)
				(justify left bottom)
				(hide yes)
			)
		)
		(property "Manufacturer" "Bourns"
			(at 285.75 86.36 0)
			(effects
				(font
					(size 1.27 1.27)
					(thickness 0.15)
				)
				(justify left bottom)
				(hide yes)
			)
		)
		(property "License" "Apache-2.0"
			(at 288.29 86.36 0)
			(effects
				(font
					(size 1.27 1.27)
					(thickness 0.15)
				)
				(justify left bottom)
				(hide yes)
			)
		)
		(property "Author" "Antmicro"
			(at 290.83 86.36 0)
			(effects
				(font
					(size 1.27 1.27)
					(thickness 0.15)
				)
				(justify left bottom)
				(hide yes)
			)
		)
		(property "Val" "8k2"
			(at 264.414 105.41 90)
			(effects
				(font
					(size 1.27 1.27)
					(thickness 0.15)
				)
				(justify right)
			)
		)
		(property "Tolerance" "1%"
			(at 273.05 86.36 0)
			(effects
				(font
					(size 1.27 1.27)
				)
				(justify left bottom)
				(hide yes)
			)
		)
		(pin "1"
		)
		(pin "2"
		)
		(instances
			(project ""
				(path ""
					(reference "R54")
					(unit 1)
				)
			)
		)
	)
	(symbol
		(lib_id "antmicroCapacitors0402:C_220n_16V_0402")
		(at 160.02 120.65 0)
		(unit 1)
		(exclude_from_sim no)
		(in_bom yes)
		(on_board yes)
		(dnp no)
		(property "Reference" "C193"
			(at 161.29 119.38 0)
			(effects
				(font
					(size 1.27 1.27)
					(thickness 0.15)
				)
				(justify right)
			)
		)
		(property "Value" "C_220n_16V_0402"
			(at 180.34 130.81 0)
			(effects
				(font
					(size 1.27 1.27)
					(thickness 0.15)
				)
				(justify left bottom)
				(hide yes)
			)
		)
		(property "Footprint" "antmicro-footprints:C_0402_1005Metric"
			(at 180.34 133.35 0)
			(effects
				(font
					(size 1.27 1.27)
					(thickness 0.15)
				)
				(justify left bottom)
				(hide yes)
			)
		)
		(property "Datasheet" "https://www.murata.com/products/productdetail?partno=GRM155R71C224KA12%23"
			(at 180.34 135.89 0)
			(effects
				(font
					(size 1.27 1.27)
					(thickness 0.15)
				)
				(justify left bottom)
				(hide yes)
			)
		)
		(property "Description" "SMD Multilayer Ceramic Capacitor, 0.22 µF, 16 V, 0402 [1005 Metric], ± 10%, X7R, GRM Series"
			(at 160.02 120.65 0)
			(effects
				(font
					(size 1.27 1.27)
				)
				(hide yes)
			)
		)
		(property "MPN" "GRM155R71C224KA12D"
			(at 180.34 138.43 0)
			(effects
				(font
					(size 1.27 1.27)
					(thickness 0.15)
				)
				(justify left bottom)
				(hide yes)
			)
		)
		(property "Manufacturer" "Murata"
			(at 180.34 140.97 0)
			(effects
				(font
					(size 1.27 1.27)
					(thickness 0.15)
				)
				(justify left bottom)
				(hide yes)
			)
		)
		(property "License" "Apache-2.0"
			(at 180.34 143.51 0)
			(effects
				(font
					(size 1.27 1.27)
					(thickness 0.15)
				)
				(justify left bottom)
				(hide yes)
			)
		)
		(property "Author" "Antmicro"
			(at 180.34 146.05 0)
			(effects
				(font
					(size 1.27 1.27)
					(thickness 0.15)
				)
				(justify left bottom)
				(hide yes)
			)
		)
		(property "Val" "220n"
			(at 163.83 119.38 0)
			(effects
				(font
					(size 1.27 1.27)
					(thickness 0.15)
				)
				(justify left)
			)
		)
		(property "Voltage" "16V"
			(at 180.34 148.59 0)
			(effects
				(font
					(size 1.27 1.27)
				)
				(justify left bottom)
				(hide yes)
			)
		)
		(property "Dielectric" "X7R"
			(at 180.34 151.13 0)
			(effects
				(font
					(size 1.27 1.27)
				)
				(justify left bottom)
				(hide yes)
			)
		)
		(pin "2"
		)
		(pin "1"
		)
		(instances
			(project "OCuLink to 10GbE adapter"
				(path ""
					(reference "C193")
					(unit 1)
				)
			)
		)
	)
	(symbol
		(lib_id "antmicroCapacitors0402:C_220n_16V_0402")
		(at 168.91 102.87 0)
		(unit 1)
		(exclude_from_sim no)
		(in_bom yes)
		(on_board yes)
		(dnp no)
		(property "Reference" "C190"
			(at 170.18 101.6 0)
			(effects
				(font
					(size 1.27 1.27)
					(thickness 0.15)
				)
				(justify right)
			)
		)
		(property "Value" "C_220n_16V_0402"
			(at 189.23 113.03 0)
			(effects
				(font
					(size 1.27 1.27)
					(thickness 0.15)
				)
				(justify left bottom)
				(hide yes)
			)
		)
		(property "Footprint" "antmicro-footprints:C_0402_1005Metric"
			(at 189.23 115.57 0)
			(effects
				(font
					(size 1.27 1.27)
					(thickness 0.15)
				)
				(justify left bottom)
				(hide yes)
			)
		)
		(property "Datasheet" "https://www.murata.com/products/productdetail?partno=GRM155R71C224KA12%23"
			(at 189.23 118.11 0)
			(effects
				(font
					(size 1.27 1.27)
					(thickness 0.15)
				)
				(justify left bottom)
				(hide yes)
			)
		)
		(property "Description" "SMD Multilayer Ceramic Capacitor, 0.22 µF, 16 V, 0402 [1005 Metric], ± 10%, X7R, GRM Series"
			(at 168.91 102.87 0)
			(effects
				(font
					(size 1.27 1.27)
				)
				(hide yes)
			)
		)
		(property "MPN" "GRM155R71C224KA12D"
			(at 189.23 120.65 0)
			(effects
				(font
					(size 1.27 1.27)
					(thickness 0.15)
				)
				(justify left bottom)
				(hide yes)
			)
		)
		(property "Manufacturer" "Murata"
			(at 189.23 123.19 0)
			(effects
				(font
					(size 1.27 1.27)
					(thickness 0.15)
				)
				(justify left bottom)
				(hide yes)
			)
		)
		(property "License" "Apache-2.0"
			(at 189.23 125.73 0)
			(effects
				(font
					(size 1.27 1.27)
					(thickness 0.15)
				)
				(justify left bottom)
				(hide yes)
			)
		)
		(property "Author" "Antmicro"
			(at 189.23 128.27 0)
			(effects
				(font
					(size 1.27 1.27)
					(thickness 0.15)
				)
				(justify left bottom)
				(hide yes)
			)
		)
		(property "Val" "220n"
			(at 172.72 101.6 0)
			(effects
				(font
					(size 1.27 1.27)
					(thickness 0.15)
				)
				(justify left)
			)
		)
		(property "Voltage" "16V"
			(at 189.23 130.81 0)
			(effects
				(font
					(size 1.27 1.27)
				)
				(justify left bottom)
				(hide yes)
			)
		)
		(property "Dielectric" "X7R"
			(at 189.23 133.35 0)
			(effects
				(font
					(size 1.27 1.27)
				)
				(justify left bottom)
				(hide yes)
			)
		)
		(pin "2"
		)
		(pin "1"
		)
		(instances
			(project "OCuLink to 10GbE adapter"
				(path ""
					(reference "C190")
					(unit 1)
				)
			)
		)
	)
	(symbol
		(lib_id "antmicroResistors0402:R_3k3_0402")
		(at 236.22 82.55 90)
		(unit 1)
		(exclude_from_sim no)
		(in_bom yes)
		(on_board yes)
		(dnp no)
		(property "Reference" "R51"
			(at 237.744 78.74 90)
			(effects
				(font
					(size 1.27 1.27)
					(thickness 0.15)
				)
				(justify right)
			)
		)
		(property "Value" "R_3k3_0402"
			(at 248.92 62.23 0)
			(effects
				(font
					(size 1.27 1.27)
					(thickness 0.15)
				)
				(justify left bottom)
				(hide yes)
			)
		)
		(property "Footprint" "antmicro-footprints:R_0402_1005Metric"
			(at 251.46 62.23 0)
			(effects
				(font
					(size 1.27 1.27)
					(thickness 0.15)
				)
				(justify left bottom)
				(hide yes)
			)
		)
		(property "Datasheet" "https://www.bourns.com/docs/product-datasheets/cr.pdf"
			(at 254 62.23 0)
			(effects
				(font
					(size 1.27 1.27)
					(thickness 0.15)
				)
				(justify left bottom)
				(hide yes)
			)
		)
		(property "Description" "SMD Chip Resistor, 3.3 kohm, ± 1%, 63 mW, 0402 [1005 Metric], Thick Film, General Purpose"
			(at 236.22 82.55 0)
			(effects
				(font
					(size 1.27 1.27)
				)
				(hide yes)
			)
		)
		(property "MPN" "CR0402-FX-3301GLF"
			(at 256.54 62.23 0)
			(effects
				(font
					(size 1.27 1.27)
					(thickness 0.15)
				)
				(justify left bottom)
				(hide yes)
			)
		)
		(property "Manufacturer" "Bourns"
			(at 259.08 62.23 0)
			(effects
				(font
					(size 1.27 1.27)
					(thickness 0.15)
				)
				(justify left bottom)
				(hide yes)
			)
		)
		(property "License" "Apache-2.0"
			(at 261.62 62.23 0)
			(effects
				(font
					(size 1.27 1.27)
					(thickness 0.15)
				)
				(justify left bottom)
				(hide yes)
			)
		)
		(property "Author" "Antmicro"
			(at 264.16 62.23 0)
			(effects
				(font
					(size 1.27 1.27)
					(thickness 0.15)
				)
				(justify left bottom)
				(hide yes)
			)
		)
		(property "Val" "3k3"
			(at 237.744 81.28 90)
			(effects
				(font
					(size 1.27 1.27)
					(thickness 0.15)
				)
				(justify right)
			)
		)
		(property "Tolerance" "1%"
			(at 246.38 62.23 0)
			(effects
				(font
					(size 1.27 1.27)
				)
				(justify left bottom)
				(hide yes)
			)
		)
		(pin "1"
		)
		(pin "2"
		)
		(instances
			(project ""
				(path ""
					(reference "R51")
					(unit 1)
				)
			)
		)
	)
	(symbol
		(lib_id "antmicroResistors0402:R_49R9_0402")
		(at 232.41 265.43 90)
		(unit 1)
		(exclude_from_sim no)
		(in_bom no)
		(on_board yes)
		(dnp yes)
		(property "Reference" "R126"
			(at 233.68 261.62 90)
			(effects
				(font
					(size 1.27 1.27)
					(thickness 0.15)
				)
				(justify right)
			)
		)
		(property "Value" "R_49R9_0402"
			(at 245.11 245.11 0)
			(effects
				(font
					(size 1.27 1.27)
					(thickness 0.15)
				)
				(justify left bottom)
				(hide yes)
			)
		)
		(property "Footprint" "antmicro-footprints:R_0402_1005Metric"
			(at 247.65 245.11 0)
			(effects
				(font
					(size 1.27 1.27)
					(thickness 0.15)
				)
				(justify left bottom)
				(hide yes)
			)
		)
		(property "Datasheet" "https://www.bourns.com/docs/product-datasheets/cr.pdf"
			(at 250.19 245.11 0)
			(effects
				(font
					(size 1.27 1.27)
					(thickness 0.15)
				)
				(justify left bottom)
				(hide yes)
			)
		)
		(property "Description" "SMD Chip Resistor, 49.9 ohm, ± 1%, 62.5 mW, 0402 [1005 Metric], Thick Film, General Purpose"
			(at 232.41 265.43 0)
			(effects
				(font
					(size 1.27 1.27)
				)
				(hide yes)
			)
		)
		(property "MPN" "CR0402-FX-49R9GLF"
			(at 252.73 245.11 0)
			(effects
				(font
					(size 1.27 1.27)
					(thickness 0.15)
				)
				(justify left bottom)
				(hide yes)
			)
		)
		(property "Manufacturer" "Bourns"
			(at 255.27 245.11 0)
			(effects
				(font
					(size 1.27 1.27)
					(thickness 0.15)
				)
				(justify left bottom)
				(hide yes)
			)
		)
		(property "License" "Apache-2.0"
			(at 257.81 245.11 0)
			(effects
				(font
					(size 1.27 1.27)
					(thickness 0.15)
				)
				(justify left bottom)
				(hide yes)
			)
		)
		(property "Author" "Antmicro"
			(at 260.35 245.11 0)
			(effects
				(font
					(size 1.27 1.27)
					(thickness 0.15)
				)
				(justify left bottom)
				(hide yes)
			)
		)
		(property "Val" "49R9"
			(at 233.68 264.16 90)
			(effects
				(font
					(size 1.27 1.27)
					(thickness 0.15)
				)
				(justify right)
			)
		)
		(property "Tolerance" "1%"
			(at 242.57 245.11 0)
			(effects
				(font
					(size 1.27 1.27)
				)
				(justify left bottom)
				(hide yes)
			)
		)
		(pin "1"
		)
		(pin "2"
		)
		(instances
			(project "oculink-to-10gbe-adapter"
				(path ""
					(reference "R126")
					(unit 1)
				)
			)
		)
	)
	(symbol
		(lib_id "antmicroResistors0402:R_100k_0402")
		(at 171.45 257.81 0)
		(unit 1)
		(exclude_from_sim no)
		(in_bom no)
		(on_board yes)
		(dnp yes)
		(property "Reference" "R118"
			(at 169.926 256.54 0)
			(effects
				(font
					(size 1.27 1.27)
					(thickness 0.15)
				)
			)
		)
		(property "Value" "R_100k_0402"
			(at 191.77 270.51 0)
			(effects
				(font
					(size 1.27 1.27)
					(thickness 0.15)
				)
				(justify left bottom)
				(hide yes)
			)
		)
		(property "Footprint" "antmicro-footprints:R_0402_1005Metric"
			(at 191.77 273.05 0)
			(effects
				(font
					(size 1.27 1.27)
					(thickness 0.15)
				)
				(justify left bottom)
				(hide yes)
			)
		)
		(property "Datasheet" "https://www.bourns.com/docs/product-datasheets/cr.pdf"
			(at 191.77 275.59 0)
			(effects
				(font
					(size 1.27 1.27)
					(thickness 0.15)
				)
				(justify left bottom)
				(hide yes)
			)
		)
		(property "Description" "SMD Chip Resistor, 100 kohm, ± 1%, 62.5 mW, 0402 [1005 Metric], Thick Film, General Purpose"
			(at 171.45 257.81 0)
			(effects
				(font
					(size 1.27 1.27)
				)
				(hide yes)
			)
		)
		(property "MPN" "CR0402-FX-1003GLF"
			(at 191.77 278.13 0)
			(effects
				(font
					(size 1.27 1.27)
					(thickness 0.15)
				)
				(justify left bottom)
				(hide yes)
			)
		)
		(property "Manufacturer" "Bourns"
			(at 191.77 280.67 0)
			(effects
				(font
					(size 1.27 1.27)
					(thickness 0.15)
				)
				(justify left bottom)
				(hide yes)
			)
		)
		(property "License" "Apache-2.0"
			(at 191.77 283.21 0)
			(effects
				(font
					(size 1.27 1.27)
					(thickness 0.15)
				)
				(justify left bottom)
				(hide yes)
			)
		)
		(property "Author" "Antmicro"
			(at 191.77 285.75 0)
			(effects
				(font
					(size 1.27 1.27)
					(thickness 0.15)
				)
				(justify left bottom)
				(hide yes)
			)
		)
		(property "Val" "100k"
			(at 178.562 256.54 0)
			(effects
				(font
					(size 1.27 1.27)
					(thickness 0.15)
				)
			)
		)
		(property "Tolerance" "1%"
			(at 191.77 267.97 0)
			(effects
				(font
					(size 1.27 1.27)
				)
				(justify left bottom)
				(hide yes)
			)
		)
		(pin "1"
		)
		(pin "2"
		)
		(instances
			(project "oculink-to-10gbe-adapter"
				(path ""
					(reference "R118")
					(unit 1)
				)
			)
			(project ""
				(path ""
					(reference "R?")
					(unit 1)
				)
			)
		)
	)
	(symbol
		(lib_id "antmicroCapacitors0402:C_100n_0402")
		(at 163.83 261.62 270)
		(mirror x)
		(unit 1)
		(exclude_from_sim no)
		(in_bom no)
		(on_board yes)
		(dnp yes)
		(property "Reference" "C199"
			(at 161.29 257.8036 90)
			(effects
				(font
					(size 1.27 1.27)
					(thickness 0.15)
				)
				(justify right)
			)
		)
		(property "Value" "C_100n_0402"
			(at 153.67 241.3 0)
			(effects
				(font
					(size 1.27 1.27)
					(thickness 0.15)
				)
				(justify left bottom)
				(hide yes)
			)
		)
		(property "Footprint" "antmicro-footprints:C_0402_1005Metric"
			(at 151.13 241.3 0)
			(effects
				(font
					(size 1.27 1.27)
					(thickness 0.15)
				)
				(justify left bottom)
				(hide yes)
			)
		)
		(property "Datasheet" "https://www.murata.com/products/productdetail?partno=GRM155R61H104KE14%23"
			(at 148.59 241.3 0)
			(effects
				(font
					(size 1.27 1.27)
					(thickness 0.15)
				)
				(justify left bottom)
				(hide yes)
			)
		)
		(property "Description" "SMD Multilayer Ceramic Capacitor, 0.1 µF, 50 V, 0402 [1005 Metric], ± 10%, X5R, GRM Series"
			(at 163.83 261.62 0)
			(effects
				(font
					(size 1.27 1.27)
				)
				(hide yes)
			)
		)
		(property "MPN" "GRM155R61H104KE14D"
			(at 146.05 241.3 0)
			(effects
				(font
					(size 1.27 1.27)
					(thickness 0.15)
				)
				(justify left bottom)
				(hide yes)
			)
		)
		(property "Manufacturer" "Murata"
			(at 143.51 241.3 0)
			(effects
				(font
					(size 1.27 1.27)
					(thickness 0.15)
				)
				(justify left bottom)
				(hide yes)
			)
		)
		(property "License" "Apache-2.0"
			(at 140.97 241.3 0)
			(effects
				(font
					(size 1.27 1.27)
					(thickness 0.15)
				)
				(justify left bottom)
				(hide yes)
			)
		)
		(property "Author" "Antmicro"
			(at 138.43 241.3 0)
			(effects
				(font
					(size 1.27 1.27)
					(thickness 0.15)
				)
				(justify left bottom)
				(hide yes)
			)
		)
		(property "Val" "100n"
			(at 161.29 260.3436 90)
			(effects
				(font
					(size 1.27 1.27)
					(thickness 0.15)
				)
				(justify right)
			)
		)
		(property "Voltage" "50V"
			(at 135.89 241.3 0)
			(effects
				(font
					(size 1.27 1.27)
				)
				(justify left bottom)
				(hide yes)
			)
		)
		(property "Dielectric" "X5R"
			(at 133.35 241.3 0)
			(effects
				(font
					(size 1.27 1.27)
				)
				(justify left bottom)
				(hide yes)
			)
		)
		(pin "1"
		)
		(pin "2"
		)
		(instances
			(project "oculink-to-10gbe-adapter"
				(path ""
					(reference "C199")
					(unit 1)
				)
			)
		)
	)
	(symbol
		(lib_id "antmicroTestPoints:Tag-Connect_TC2050-IDC-NL_2x5_P1.27mm")
		(at 274.32 139.7 0)
		(unit 1)
		(exclude_from_sim no)
		(in_bom no)
		(on_board yes)
		(dnp yes)
		(fields_autoplaced yes)
		(property "Reference" "J7"
			(at 290.195 132.08 0)
			(effects
				(font
					(size 1.27 1.27)
					(thickness 0.15)
				)
			)
		)
		(property "Value" "Tag-Connect_TC2050-IDC-NL_2x5_P1.27mm"
			(at 313.69 143.51 0)
			(effects
				(font
					(size 1.27 1.27)
					(thickness 0.15)
				)
				(justify left bottom)
				(hide yes)
			)
		)
		(property "Footprint" "antmicro-footprints:Tag-Connect_TC2050-IDC-NL_2x5_P1.27mm"
			(at 313.69 146.05 0)
			(effects
				(font
					(size 1.27 1.27)
					(thickness 0.15)
				)
				(justify left bottom)
				(hide yes)
			)
		)
		(property "Datasheet" "https://www.tag-connect.com/wp-content/uploads/bsk-pdf-manager/TC2050-IDC-NL_Datasheet_8.pdf"
			(at 313.69 148.59 0)
			(effects
				(font
					(size 1.27 1.27)
					(thickness 0.15)
				)
				(justify left bottom)
				(hide yes)
			)
		)
		(property "Description" "Tag Connect 2x5 1.27mm terminal"
			(at 313.69 161.29 0)
			(effects
				(font
					(size 1.27 1.27)
				)
				(justify left bottom)
				(hide yes)
			)
		)
		(property "MPN" "TC2050-IDC-NL"
			(at 290.195 134.62 0)
			(effects
				(font
					(size 1.27 1.27)
					(thickness 0.15)
				)
			)
		)
		(property "Manufacturer" "Tag Connect"
			(at 313.69 153.67 0)
			(effects
				(font
					(size 1.27 1.27)
					(thickness 0.15)
				)
				(justify left bottom)
				(hide yes)
			)
		)
		(property "Author" "Antmicro"
			(at 313.69 156.21 0)
			(effects
				(font
					(size 1.27 1.27)
					(thickness 0.15)
				)
				(justify left bottom)
				(hide yes)
			)
		)
		(property "License" "Apache-2.0"
			(at 313.69 158.75 0)
			(effects
				(font
					(size 1.27 1.27)
					(thickness 0.15)
				)
				(justify left bottom)
				(hide yes)
			)
		)
		(pin "3"
			(alternate "GND")
		)
		(pin "5"
			(alternate "GND")
		)
		(pin "8"
			(alternate "JTAG_TDI")
		)
		(pin "7"
			(alternate "NC")
		)
		(pin "6"
			(alternate "JTAG_TDO")
		)
		(pin "10"
			(alternate "JTAG_~{RESET}")
		)
		(pin "4"
			(alternate "JTAG_TCK")
		)
		(pin "2"
			(alternate "JTAG_TMS")
		)
		(pin "9"
			(alternate "GND")
		)
		(pin "1"
			(alternate "3V3")
		)
		(instances
			(project ""
				(path ""
					(reference "J7")
					(unit 1)
				)
			)
		)
	)
	(symbol
		(lib_id "antmicroResistors0402:R_0R_0402")
		(at 250.19 257.81 0)
		(unit 1)
		(exclude_from_sim no)
		(in_bom no)
		(on_board yes)
		(dnp yes)
		(property "Reference" "R122"
			(at 247.142 256.54 0)
			(effects
				(font
					(size 1.27 1.27)
					(thickness 0.15)
				)
			)
		)
		(property "Value" "R_0R_0402"
			(at 270.51 270.51 0)
			(effects
				(font
					(size 1.27 1.27)
					(thickness 0.15)
				)
				(justify left bottom)
				(hide yes)
			)
		)
		(property "Footprint" "antmicro-footprints:R_0402_1005Metric"
			(at 270.51 273.05 0)
			(effects
				(font
					(size 1.27 1.27)
					(thickness 0.15)
				)
				(justify left bottom)
				(hide yes)
			)
		)
		(property "Datasheet" "https://industrial.panasonic.com/cdbs/www-data/pdf/RDA0000/AOA0000C301.pdf"
			(at 270.51 275.59 0)
			(effects
				(font
					(size 1.27 1.27)
					(thickness 0.15)
				)
				(justify left bottom)
				(hide yes)
			)
		)
		(property "Description" "SMD Chip Resistor, Jumper, 0 ohm, 100 mW, 0402 [1005 Metric], Thick Film, General Purpose"
			(at 270.51 290.83 0)
			(effects
				(font
					(size 1.27 1.27)
				)
				(justify left bottom)
				(hide yes)
			)
		)
		(property "MPN" "ERJ2GE0R00X"
			(at 270.51 278.13 0)
			(effects
				(font
					(size 1.27 1.27)
					(thickness 0.15)
				)
				(justify left bottom)
				(hide yes)
			)
		)
		(property "Manufacturer" "Panasonic"
			(at 270.51 280.67 0)
			(effects
				(font
					(size 1.27 1.27)
					(thickness 0.15)
				)
				(justify left bottom)
				(hide yes)
			)
		)
		(property "License" "Apache-2.0"
			(at 270.51 283.21 0)
			(effects
				(font
					(size 1.27 1.27)
					(thickness 0.15)
				)
				(justify left bottom)
				(hide yes)
			)
		)
		(property "Author" "Antmicro"
			(at 270.51 285.75 0)
			(effects
				(font
					(size 1.27 1.27)
					(thickness 0.15)
				)
				(justify left bottom)
				(hide yes)
			)
		)
		(property "Val" "0R"
			(at 256.54 256.54 0)
			(effects
				(font
					(size 1.27 1.27)
					(thickness 0.15)
				)
			)
		)
		(property "Tolerance" "~"
			(at 270.51 267.97 0)
			(effects
				(font
					(size 1.27 1.27)
				)
				(justify left bottom)
				(hide yes)
			)
		)
		(property "Current" "1A"
			(at 270.51 288.29 0)
			(effects
				(font
					(size 1.27 1.27)
					(thickness 0.15)
				)
				(justify left bottom)
				(hide yes)
			)
		)
		(pin "2"
		)
		(pin "1"
		)
		(instances
			(project "oculink-to-10gbe-adapter"
				(path ""
					(reference "R122")
					(unit 1)
				)
			)
		)
	)
	(symbol
		(lib_id "antmicroCapacitors0402:C_220n_16V_0402")
		(at 168.91 118.11 0)
		(unit 1)
		(exclude_from_sim no)
		(in_bom yes)
		(on_board yes)
		(dnp no)
		(property "Reference" "C192"
			(at 170.18 116.84 0)
			(effects
				(font
					(size 1.27 1.27)
					(thickness 0.15)
				)
				(justify right)
			)
		)
		(property "Value" "C_220n_16V_0402"
			(at 189.23 128.27 0)
			(effects
				(font
					(size 1.27 1.27)
					(thickness 0.15)
				)
				(justify left bottom)
				(hide yes)
			)
		)
		(property "Footprint" "antmicro-footprints:C_0402_1005Metric"
			(at 189.23 130.81 0)
			(effects
				(font
					(size 1.27 1.27)
					(thickness 0.15)
				)
				(justify left bottom)
				(hide yes)
			)
		)
		(property "Datasheet" "https://www.murata.com/products/productdetail?partno=GRM155R71C224KA12%23"
			(at 189.23 133.35 0)
			(effects
				(font
					(size 1.27 1.27)
					(thickness 0.15)
				)
				(justify left bottom)
				(hide yes)
			)
		)
		(property "Description" "SMD Multilayer Ceramic Capacitor, 0.22 µF, 16 V, 0402 [1005 Metric], ± 10%, X7R, GRM Series"
			(at 168.91 118.11 0)
			(effects
				(font
					(size 1.27 1.27)
				)
				(hide yes)
			)
		)
		(property "MPN" "GRM155R71C224KA12D"
			(at 189.23 135.89 0)
			(effects
				(font
					(size 1.27 1.27)
					(thickness 0.15)
				)
				(justify left bottom)
				(hide yes)
			)
		)
		(property "Manufacturer" "Murata"
			(at 189.23 138.43 0)
			(effects
				(font
					(size 1.27 1.27)
					(thickness 0.15)
				)
				(justify left bottom)
				(hide yes)
			)
		)
		(property "License" "Apache-2.0"
			(at 189.23 140.97 0)
			(effects
				(font
					(size 1.27 1.27)
					(thickness 0.15)
				)
				(justify left bottom)
				(hide yes)
			)
		)
		(property "Author" "Antmicro"
			(at 189.23 143.51 0)
			(effects
				(font
					(size 1.27 1.27)
					(thickness 0.15)
				)
				(justify left bottom)
				(hide yes)
			)
		)
		(property "Val" "220n"
			(at 172.72 116.84 0)
			(effects
				(font
					(size 1.27 1.27)
					(thickness 0.15)
				)
				(justify left)
			)
		)
		(property "Voltage" "16V"
			(at 189.23 146.05 0)
			(effects
				(font
					(size 1.27 1.27)
				)
				(justify left bottom)
				(hide yes)
			)
		)
		(property "Dielectric" "X7R"
			(at 189.23 148.59 0)
			(effects
				(font
					(size 1.27 1.27)
				)
				(justify left bottom)
				(hide yes)
			)
		)
		(pin "2"
		)
		(pin "1"
		)
		(instances
			(project "OCuLink to 10GbE adapter"
				(path ""
					(reference "C192")
					(unit 1)
				)
			)
		)
	)
	(symbol
		(lib_id "antmicroResistors0402:R_49R9_0402")
		(at 224.79 265.43 90)
		(unit 1)
		(exclude_from_sim no)
		(in_bom no)
		(on_board yes)
		(dnp yes)
		(property "Reference" "R125"
			(at 226.06 261.62 90)
			(effects
				(font
					(size 1.27 1.27)
					(thickness 0.15)
				)
				(justify right)
			)
		)
		(property "Value" "R_49R9_0402"
			(at 237.49 245.11 0)
			(effects
				(font
					(size 1.27 1.27)
					(thickness 0.15)
				)
				(justify left bottom)
				(hide yes)
			)
		)
		(property "Footprint" "antmicro-footprints:R_0402_1005Metric"
			(at 240.03 245.11 0)
			(effects
				(font
					(size 1.27 1.27)
					(thickness 0.15)
				)
				(justify left bottom)
				(hide yes)
			)
		)
		(property "Datasheet" "https://www.bourns.com/docs/product-datasheets/cr.pdf"
			(at 242.57 245.11 0)
			(effects
				(font
					(size 1.27 1.27)
					(thickness 0.15)
				)
				(justify left bottom)
				(hide yes)
			)
		)
		(property "Description" "SMD Chip Resistor, 49.9 ohm, ± 1%, 62.5 mW, 0402 [1005 Metric], Thick Film, General Purpose"
			(at 224.79 265.43 0)
			(effects
				(font
					(size 1.27 1.27)
				)
				(hide yes)
			)
		)
		(property "MPN" "CR0402-FX-49R9GLF"
			(at 245.11 245.11 0)
			(effects
				(font
					(size 1.27 1.27)
					(thickness 0.15)
				)
				(justify left bottom)
				(hide yes)
			)
		)
		(property "Manufacturer" "Bourns"
			(at 247.65 245.11 0)
			(effects
				(font
					(size 1.27 1.27)
					(thickness 0.15)
				)
				(justify left bottom)
				(hide yes)
			)
		)
		(property "License" "Apache-2.0"
			(at 250.19 245.11 0)
			(effects
				(font
					(size 1.27 1.27)
					(thickness 0.15)
				)
				(justify left bottom)
				(hide yes)
			)
		)
		(property "Author" "Antmicro"
			(at 252.73 245.11 0)
			(effects
				(font
					(size 1.27 1.27)
					(thickness 0.15)
				)
				(justify left bottom)
				(hide yes)
			)
		)
		(property "Val" "49R9"
			(at 226.06 264.16 90)
			(effects
				(font
					(size 1.27 1.27)
					(thickness 0.15)
				)
				(justify right)
			)
		)
		(property "Tolerance" "1%"
			(at 234.95 245.11 0)
			(effects
				(font
					(size 1.27 1.27)
				)
				(justify left bottom)
				(hide yes)
			)
		)
		(pin "1"
		)
		(pin "2"
		)
		(instances
			(project "oculink-to-10gbe-adapter"
				(path ""
					(reference "R125")
					(unit 1)
				)
			)
		)
	)
	(symbol
		(lib_id "antmicropower:GND")
		(at 271.78 109.22 0)
		(unit 1)
		(exclude_from_sim no)
		(in_bom yes)
		(on_board yes)
		(dnp no)
		(property "Reference" "#PWR0247"
			(at 280.67 111.76 0)
			(effects
				(font
					(size 1.27 1.27)
					(thickness 0.15)
				)
				(justify left bottom)
				(hide yes)
			)
		)
		(property "Value" "GND"
			(at 271.78 113.03 0)
			(effects
				(font
					(size 1.27 1.27)
					(thickness 0.15)
				)
			)
		)
		(property "Footprint" ""
			(at 280.67 116.84 0)
			(effects
				(font
					(size 1.27 1.27)
					(thickness 0.15)
				)
				(justify left bottom)
				(hide yes)
			)
		)
		(property "Datasheet" ""
			(at 280.67 121.92 0)
			(effects
				(font
					(size 1.27 1.27)
					(thickness 0.15)
				)
				(justify left bottom)
				(hide yes)
			)
		)
		(property "Description" ""
			(at 271.78 109.22 0)
			(effects
				(font
					(size 1.27 1.27)
				)
				(hide yes)
			)
		)
		(property "Author" "Antmicro"
			(at 280.67 116.84 0)
			(effects
				(font
					(size 1.27 1.27)
					(thickness 0.15)
				)
				(justify left bottom)
				(hide yes)
			)
		)
		(property "License" "Apache-2.0"
			(at 280.67 119.38 0)
			(effects
				(font
					(size 1.27 1.27)
					(thickness 0.15)
				)
				(justify left bottom)
				(hide yes)
			)
		)
		(pin "1"
		)
		(instances
			(project "OCuLink to 10GbE adapter"
				(path ""
					(reference "#PWR0247")
					(unit 1)
				)
			)
		)
	)
	(symbol
		(lib_id "antmicroResistors0402:R_33R_0402")
		(at 215.9 257.81 0)
		(unit 1)
		(exclude_from_sim no)
		(in_bom no)
		(on_board yes)
		(dnp yes)
		(property "Reference" "R124"
			(at 213.36 256.54 0)
			(effects
				(font
					(size 1.27 1.27)
					(thickness 0.15)
				)
			)
		)
		(property "Value" "R_33R_0402"
			(at 236.22 270.51 0)
			(effects
				(font
					(size 1.27 1.27)
					(thickness 0.15)
				)
				(justify left bottom)
				(hide yes)
			)
		)
		(property "Footprint" "antmicro-footprints:R_0402_1005Metric"
			(at 236.22 273.05 0)
			(effects
				(font
					(size 1.27 1.27)
					(thickness 0.15)
				)
				(justify left bottom)
				(hide yes)
			)
		)
		(property "Datasheet" "https://www.bourns.com/docs/product-datasheets/cr.pdf"
			(at 236.22 275.59 0)
			(effects
				(font
					(size 1.27 1.27)
					(thickness 0.15)
				)
				(justify left bottom)
				(hide yes)
			)
		)
		(property "Description" "SMD Chip Resistor, 33 ohm, ± 1%, 62.5 mW, 0402 [1005 Metric], Thick Film, General Purpose"
			(at 215.9 257.81 0)
			(effects
				(font
					(size 1.27 1.27)
				)
				(hide yes)
			)
		)
		(property "MPN" "CR0402-FX-33R0GLF"
			(at 236.22 278.13 0)
			(effects
				(font
					(size 1.27 1.27)
					(thickness 0.15)
				)
				(justify left bottom)
				(hide yes)
			)
		)
		(property "Manufacturer" "Bourns"
			(at 236.22 280.67 0)
			(effects
				(font
					(size 1.27 1.27)
					(thickness 0.15)
				)
				(justify left bottom)
				(hide yes)
			)
		)
		(property "License" "Apache-2.0"
			(at 236.22 283.21 0)
			(effects
				(font
					(size 1.27 1.27)
					(thickness 0.15)
				)
				(justify left bottom)
				(hide yes)
			)
		)
		(property "Author" "Antmicro"
			(at 236.22 285.75 0)
			(effects
				(font
					(size 1.27 1.27)
					(thickness 0.15)
				)
				(justify left bottom)
				(hide yes)
			)
		)
		(property "Val" "33R"
			(at 222.885 256.54 0)
			(effects
				(font
					(size 1.27 1.27)
					(thickness 0.15)
				)
			)
		)
		(property "Tolerance" "1%"
			(at 236.22 267.97 0)
			(effects
				(font
					(size 1.27 1.27)
				)
				(justify left bottom)
				(hide yes)
			)
		)
		(pin "2"
		)
		(pin "1"
		)
		(instances
			(project "oculink-to-10gbe-adapter"
				(path ""
					(reference "R124")
					(unit 1)
				)
			)
		)
	)
	(symbol
		(lib_id "antmicroResistors0402:R_33R_0402")
		(at 215.9 255.27 0)
		(unit 1)
		(exclude_from_sim no)
		(in_bom no)
		(on_board yes)
		(dnp yes)
		(property "Reference" "R123"
			(at 213.36 254 0)
			(effects
				(font
					(size 1.27 1.27)
					(thickness 0.15)
				)
			)
		)
		(property "Value" "R_33R_0402"
			(at 236.22 267.97 0)
			(effects
				(font
					(size 1.27 1.27)
					(thickness 0.15)
				)
				(justify left bottom)
				(hide yes)
			)
		)
		(property "Footprint" "antmicro-footprints:R_0402_1005Metric"
			(at 236.22 270.51 0)
			(effects
				(font
					(size 1.27 1.27)
					(thickness 0.15)
				)
				(justify left bottom)
				(hide yes)
			)
		)
		(property "Datasheet" "https://www.bourns.com/docs/product-datasheets/cr.pdf"
			(at 236.22 273.05 0)
			(effects
				(font
					(size 1.27 1.27)
					(thickness 0.15)
				)
				(justify left bottom)
				(hide yes)
			)
		)
		(property "Description" "SMD Chip Resistor, 33 ohm, ± 1%, 62.5 mW, 0402 [1005 Metric], Thick Film, General Purpose"
			(at 215.9 255.27 0)
			(effects
				(font
					(size 1.27 1.27)
				)
				(hide yes)
			)
		)
		(property "MPN" "CR0402-FX-33R0GLF"
			(at 236.22 275.59 0)
			(effects
				(font
					(size 1.27 1.27)
					(thickness 0.15)
				)
				(justify left bottom)
				(hide yes)
			)
		)
		(property "Manufacturer" "Bourns"
			(at 236.22 278.13 0)
			(effects
				(font
					(size 1.27 1.27)
					(thickness 0.15)
				)
				(justify left bottom)
				(hide yes)
			)
		)
		(property "License" "Apache-2.0"
			(at 236.22 280.67 0)
			(effects
				(font
					(size 1.27 1.27)
					(thickness 0.15)
				)
				(justify left bottom)
				(hide yes)
			)
		)
		(property "Author" "Antmicro"
			(at 236.22 283.21 0)
			(effects
				(font
					(size 1.27 1.27)
					(thickness 0.15)
				)
				(justify left bottom)
				(hide yes)
			)
		)
		(property "Val" "33R"
			(at 222.885 254 0)
			(effects
				(font
					(size 1.27 1.27)
					(thickness 0.15)
				)
			)
		)
		(property "Tolerance" "1%"
			(at 236.22 265.43 0)
			(effects
				(font
					(size 1.27 1.27)
				)
				(justify left bottom)
				(hide yes)
			)
		)
		(pin "2"
		)
		(pin "1"
		)
		(instances
			(project "oculink-to-10gbe-adapter"
				(path ""
					(reference "R123")
					(unit 1)
				)
			)
		)
	)
	(symbol
		(lib_id "antmicropower:GND")
		(at 271.78 152.4 0)
		(unit 1)
		(exclude_from_sim no)
		(in_bom yes)
		(on_board yes)
		(dnp no)
		(property "Reference" "#PWR0248"
			(at 280.67 154.94 0)
			(effects
				(font
					(size 1.27 1.27)
					(thickness 0.15)
				)
				(justify left bottom)
				(hide yes)
			)
		)
		(property "Value" "GND"
			(at 271.78 156.21 0)
			(effects
				(font
					(size 1.27 1.27)
					(thickness 0.15)
				)
			)
		)
		(property "Footprint" ""
			(at 280.67 160.02 0)
			(effects
				(font
					(size 1.27 1.27)
					(thickness 0.15)
				)
				(justify left bottom)
				(hide yes)
			)
		)
		(property "Datasheet" ""
			(at 280.67 165.1 0)
			(effects
				(font
					(size 1.27 1.27)
					(thickness 0.15)
				)
				(justify left bottom)
				(hide yes)
			)
		)
		(property "Description" ""
			(at 271.78 152.4 0)
			(effects
				(font
					(size 1.27 1.27)
				)
				(hide yes)
			)
		)
		(property "Author" "Antmicro"
			(at 280.67 160.02 0)
			(effects
				(font
					(size 1.27 1.27)
					(thickness 0.15)
				)
				(justify left bottom)
				(hide yes)
			)
		)
		(property "License" "Apache-2.0"
			(at 280.67 162.56 0)
			(effects
				(font
					(size 1.27 1.27)
					(thickness 0.15)
				)
				(justify left bottom)
				(hide yes)
			)
		)
		(pin "1"
		)
		(instances
			(project "OCuLink to 10GbE adapter"
				(path ""
					(reference "#PWR0248")
					(unit 1)
				)
			)
		)
	)
	(symbol
		(lib_id "antmicropower:GND")
		(at 308.61 152.4 0)
		(unit 1)
		(exclude_from_sim no)
		(in_bom yes)
		(on_board yes)
		(dnp no)
		(property "Reference" "#PWR0249"
			(at 317.5 154.94 0)
			(effects
				(font
					(size 1.27 1.27)
					(thickness 0.15)
				)
				(justify left bottom)
				(hide yes)
			)
		)
		(property "Value" "GND"
			(at 308.61 156.21 0)
			(effects
				(font
					(size 1.27 1.27)
					(thickness 0.15)
				)
			)
		)
		(property "Footprint" ""
			(at 317.5 160.02 0)
			(effects
				(font
					(size 1.27 1.27)
					(thickness 0.15)
				)
				(justify left bottom)
				(hide yes)
			)
		)
		(property "Datasheet" ""
			(at 317.5 165.1 0)
			(effects
				(font
					(size 1.27 1.27)
					(thickness 0.15)
				)
				(justify left bottom)
				(hide yes)
			)
		)
		(property "Description" ""
			(at 308.61 152.4 0)
			(effects
				(font
					(size 1.27 1.27)
				)
				(hide yes)
			)
		)
		(property "Author" "Antmicro"
			(at 317.5 160.02 0)
			(effects
				(font
					(size 1.27 1.27)
					(thickness 0.15)
				)
				(justify left bottom)
				(hide yes)
			)
		)
		(property "License" "Apache-2.0"
			(at 317.5 162.56 0)
			(effects
				(font
					(size 1.27 1.27)
					(thickness 0.15)
				)
				(justify left bottom)
				(hide yes)
			)
		)
		(pin "1"
		)
		(instances
			(project "OCuLink to 10GbE adapter"
				(path ""
					(reference "#PWR0249")
					(unit 1)
				)
			)
		)
	)
	(symbol
		(lib_id "antmicroCapacitors0402:C_220n_16V_0402")
		(at 160.02 151.13 0)
		(unit 1)
		(exclude_from_sim no)
		(in_bom yes)
		(on_board yes)
		(dnp no)
		(property "Reference" "C197"
			(at 161.29 149.86 0)
			(effects
				(font
					(size 1.27 1.27)
					(thickness 0.15)
				)
				(justify right)
			)
		)
		(property "Value" "C_220n_16V_0402"
			(at 180.34 161.29 0)
			(effects
				(font
					(size 1.27 1.27)
					(thickness 0.15)
				)
				(justify left bottom)
				(hide yes)
			)
		)
		(property "Footprint" "antmicro-footprints:C_0402_1005Metric"
			(at 180.34 163.83 0)
			(effects
				(font
					(size 1.27 1.27)
					(thickness 0.15)
				)
				(justify left bottom)
				(hide yes)
			)
		)
		(property "Datasheet" "https://www.murata.com/products/productdetail?partno=GRM155R71C224KA12%23"
			(at 180.34 166.37 0)
			(effects
				(font
					(size 1.27 1.27)
					(thickness 0.15)
				)
				(justify left bottom)
				(hide yes)
			)
		)
		(property "Description" "SMD Multilayer Ceramic Capacitor, 0.22 µF, 16 V, 0402 [1005 Metric], ± 10%, X7R, GRM Series"
			(at 160.02 151.13 0)
			(effects
				(font
					(size 1.27 1.27)
				)
				(hide yes)
			)
		)
		(property "MPN" "GRM155R71C224KA12D"
			(at 180.34 168.91 0)
			(effects
				(font
					(size 1.27 1.27)
					(thickness 0.15)
				)
				(justify left bottom)
				(hide yes)
			)
		)
		(property "Manufacturer" "Murata"
			(at 180.34 171.45 0)
			(effects
				(font
					(size 1.27 1.27)
					(thickness 0.15)
				)
				(justify left bottom)
				(hide yes)
			)
		)
		(property "License" "Apache-2.0"
			(at 180.34 173.99 0)
			(effects
				(font
					(size 1.27 1.27)
					(thickness 0.15)
				)
				(justify left bottom)
				(hide yes)
			)
		)
		(property "Author" "Antmicro"
			(at 180.34 176.53 0)
			(effects
				(font
					(size 1.27 1.27)
					(thickness 0.15)
				)
				(justify left bottom)
				(hide yes)
			)
		)
		(property "Val" "220n"
			(at 163.83 149.86 0)
			(effects
				(font
					(size 1.27 1.27)
					(thickness 0.15)
				)
				(justify left)
			)
		)
		(property "Voltage" "16V"
			(at 180.34 179.07 0)
			(effects
				(font
					(size 1.27 1.27)
				)
				(justify left bottom)
				(hide yes)
			)
		)
		(property "Dielectric" "X7R"
			(at 180.34 181.61 0)
			(effects
				(font
					(size 1.27 1.27)
				)
				(justify left bottom)
				(hide yes)
			)
		)
		(pin "2"
		)
		(pin "1"
		)
		(instances
			(project "OCuLink to 10GbE adapter"
				(path ""
					(reference "C197")
					(unit 1)
				)
			)
		)
	)
	(symbol
		(lib_id "antmicropower:GND")
		(at 180.34 261.62 0)
		(mirror y)
		(unit 1)
		(exclude_from_sim no)
		(in_bom yes)
		(on_board yes)
		(dnp no)
		(property "Reference" "#PWR0421"
			(at 180.34 267.97 0)
			(effects
				(font
					(size 1.27 1.27)
				)
				(justify left bottom)
				(hide yes)
			)
		)
		(property "Value" "GND"
			(at 180.34 265.43 0)
			(effects
				(font
					(size 1.27 1.27)
				)
			)
		)
		(property "Footprint" ""
			(at 180.34 261.62 0)
			(effects
				(font
					(size 1.27 1.27)
				)
				(justify left bottom)
				(hide yes)
			)
		)
		(property "Datasheet" ""
			(at 180.34 261.62 0)
			(effects
				(font
					(size 1.27 1.27)
				)
				(justify left bottom)
				(hide yes)
			)
		)
		(property "Description" ""
			(at 180.34 261.62 0)
			(effects
				(font
					(size 1.27 1.27)
				)
				(hide yes)
			)
		)
		(property "Author" "Antmicro"
			(at 171.45 269.24 0)
			(effects
				(font
					(size 1.27 1.27)
					(thickness 0.15)
				)
				(justify left bottom)
				(hide yes)
			)
		)
		(property "License" "Apache-2.0"
			(at 171.45 271.78 0)
			(effects
				(font
					(size 1.27 1.27)
					(thickness 0.15)
				)
				(justify left bottom)
				(hide yes)
			)
		)
		(pin "1"
		)
		(instances
			(project "oculink-to-10gbe-adapter"
				(path ""
					(reference "#PWR0421")
					(unit 1)
				)
			)
		)
	)
	(symbol
		(lib_id "antmicroInterfaceControllers:EZX710AT2_S_LMR5")
		(at 198.12 87.63 0)
		(unit 1)
		(exclude_from_sim no)
		(in_bom yes)
		(on_board yes)
		(dnp no)
		(fields_autoplaced yes)
		(property "Reference" "U9"
			(at 215.9 80.01 0)
			(effects
				(font
					(size 1.27 1.27)
					(thickness 0.15)
				)
			)
		)
		(property "Value" "EZX710AT2_S_LMR5"
			(at 274.32 92.71 0)
			(effects
				(font
					(size 1.27 1.27)
					(thickness 0.15)
				)
				(justify left bottom)
				(hide yes)
			)
		)
		(property "Footprint" "antmicro-footprints:FCBGA-503_22x22mm_Layout21x24_P1mm"
			(at 274.32 95.25 0)
			(effects
				(font
					(size 1.27 1.27)
					(thickness 0.15)
				)
				(justify left bottom)
				(hide yes)
			)
		)
		(property "Datasheet" "https://www.google.com/url?sa=t&source=web&rct=j&opi=89978449&url=https://cdrdv2-public.intel.com/596333/596333_X710-TM4_Datasheet_v_2_4.pdf&ved=2ahUKEwiSuv20_sCOAxXVCRAIHdxGO_UQFnoECBEQAQ&usg=AOvVaw1CjGyrGWE8ZvOdw4VBsY6U"
			(at 274.32 97.79 0)
			(effects
				(font
					(size 1.27 1.27)
					(thickness 0.15)
				)
				(justify left bottom)
				(hide yes)
			)
		)
		(property "Description" "Ethernet ICs Intel Ethernet Controller 10 Gigabit X7"
			(at 274.32 100.33 0)
			(effects
				(font
					(size 1.27 1.27)
					(thickness 0.15)
				)
				(justify left bottom)
				(hide yes)
			)
		)
		(property "MPN" "EZX710AT2 S LMR5"
			(at 215.9 82.55 0)
			(effects
				(font
					(size 1.27 1.27)
					(thickness 0.15)
				)
			)
		)
		(property "Manufacturer" "Intel"
			(at 274.32 102.87 0)
			(effects
				(font
					(size 1.27 1.27)
					(thickness 0.15)
				)
				(justify left bottom)
				(hide yes)
			)
		)
		(property "Author" "Antmicro"
			(at 274.32 105.41 0)
			(effects
				(font
					(size 1.27 1.27)
					(thickness 0.15)
				)
				(justify left bottom)
				(hide yes)
			)
		)
		(property "License" "Apache-2.0"
			(at 274.32 107.95 0)
			(effects
				(font
					(size 1.27 1.27)
					(thickness 0.15)
				)
				(justify left bottom)
				(hide yes)
			)
		)
		(pin "A13"
		)
		(pin "AA27"
		)
		(pin "W5"
		)
		(pin "P28"
		)
		(pin "U37"
		)
		(pin "E7"
		)
		(pin "M30"
		)
		(pin "T22"
		)
		(pin "AD32"
		)
		(pin "F14"
		)
		(pin "U7"
		)
		(pin "AB6"
		)
		(pin "AD10"
		)
		(pin "P26"
		)
		(pin "M28"
		)
		(pin "W23"
		)
		(pin "J7"
		)
		(pin "B14"
		)
		(pin "L33"
		)
		(pin "G3"
		)
		(pin "D42"
		)
		(pin "D30"
		)
		(pin "J39"
		)
		(pin "K14"
		)
		(pin "G31"
		)
		(pin "C23"
		)
		(pin "C37"
		)
		(pin "V4"
		)
		(pin "D2"
		)
		(pin "A29"
		)
		(pin "AA41"
		)
		(pin "N31"
		)
		(pin "R39"
		)
		(pin "Y26"
		)
		(pin "T28"
		)
		(pin "K10"
		)
		(pin "K40"
		)
		(pin "L13"
		)
		(pin "C25"
		)
		(pin "N13"
		)
		(pin "W25"
		)
		(pin "G35"
		)
		(pin "W15"
		)
		(pin "W17"
		)
		(pin "G13"
		)
		(pin "J27"
		)
		(pin "AC27"
		)
		(pin "AC41"
		)
		(pin "J19"
		)
		(pin "J29"
		)
		(pin "H32"
		)
		(pin "H28"
		)
		(pin "C33"
		)
		(pin "W21"
		)
		(pin "N27"
		)
		(pin "N17"
		)
		(pin "C13"
		)
		(pin "P32"
		)
		(pin "D12"
		)
		(pin "L29"
		)
		(pin "U41"
		)
		(pin "Y6"
		)
		(pin "K16"
		)
		(pin "Y36"
		)
		(pin "P16"
		)
		(pin "C15"
		)
		(pin "R35"
		)
		(pin "L19"
		)
		(pin "H30"
		)
		(pin "J13"
		)
		(pin "P18"
		)
		(pin "R19"
		)
		(pin "N29"
		)
		(pin "P14"
		)
		(pin "R17"
		)
		(pin "C29"
		)
		(pin "N15"
		)
		(pin "K38"
		)
		(pin "C27"
		)
		(pin "A31"
		)
		(pin "Y40"
		)
		(pin "L39"
		)
		(pin "E29"
		)
		(pin "A21"
		)
		(pin "Y4"
		)
		(pin "W33"
		)
		(pin "P22"
		)
		(pin "A23"
		)
		(pin "P20"
		)
		(pin "T20"
		)
		(pin "J3"
		)
		(pin "Y8"
		)
		(pin "W19"
		)
		(pin "AA13"
		)
		(pin "H6"
		)
		(pin "K36"
		)
		(pin "A3"
		)
		(pin "C11"
		)
		(pin "L1"
		)
		(pin "F30"
		)
		(pin "M24"
		)
		(pin "B16"
		)
		(pin "AA21"
		)
		(pin "G15"
		)
		(pin "W41"
		)
		(pin "Y42"
		)
		(pin "B20"
		)
		(pin "U9"
		)
		(pin "U11"
		)
		(pin "L25"
		)
		(pin "U17"
		)
		(pin "L9"
		)
		(pin "U13"
		)
		(pin "U15"
		)
		(pin "G21"
		)
		(pin "D38"
		)
		(pin "U21"
		)
		(pin "L27"
		)
		(pin "F32"
		)
		(pin "R37"
		)
		(pin "B2"
		)
		(pin "T2"
		)
		(pin "E3"
		)
		(pin "B4"
		)
		(pin "Y2"
		)
		(pin "P38"
		)
		(pin "H36"
		)
		(pin "E21"
		)
		(pin "AD30"
		)
		(pin "A19"
		)
		(pin "AC9"
		)
		(pin "W3"
		)
		(pin "G19"
		)
		(pin "B40"
		)
		(pin "F40"
		)
		(pin "D28"
		)
		(pin "F28"
		)
		(pin "F36"
		)
		(pin "C5"
		)
		(pin "P12"
		)
		(pin "D40"
		)
		(pin "U1"
		)
		(pin "K22"
		)
		(pin "K20"
		)
		(pin "M10"
		)
		(pin "B22"
		)
		(pin "H16"
		)
		(pin "V16"
		)
		(pin "M16"
		)
		(pin "G41"
		)
		(pin "F26"
		)
		(pin "AC33"
		)
		(pin "V18"
		)
		(pin "W11"
		)
		(pin "M20"
		)
		(pin "P8"
		)
		(pin "M18"
		)
		(pin "U5"
		)
		(pin "T8"
		)
		(pin "V14"
		)
		(pin "T34"
		)
		(pin "H34"
		)
		(pin "F24"
		)
		(pin "C19"
		)
		(pin "K18"
		)
		(pin "H26"
		)
		(pin "M14"
		)
		(pin "V2"
		)
		(pin "R11"
		)
		(pin "V12"
		)
		(pin "C41"
		)
		(pin "D26"
		)
		(pin "P10"
		)
		(pin "F42"
		)
		(pin "F34"
		)
		(pin "B32"
		)
		(pin "D24"
		)
		(pin "E33"
		)
		(pin "D36"
		)
		(pin "C9"
		)
		(pin "C31"
		)
		(pin "C17"
		)
		(pin "L35"
		)
		(pin "R3"
		)
		(pin "K8"
		)
		(pin "R21"
		)
		(pin "E31"
		)
		(pin "M12"
		)
		(pin "W9"
		)
		(pin "U19"
		)
		(pin "R27"
		)
		(pin "A7"
		)
		(pin "R5"
		)
		(pin "L21"
		)
		(pin "T12"
		)
		(pin "AD12"
		)
		(pin "F16"
		)
		(pin "U35"
		)
		(pin "AC23"
		)
		(pin "H4"
		)
		(pin "AB14"
		)
		(pin "R29"
		)
		(pin "T16"
		)
		(pin "F6"
		)
		(pin "AC7"
		)
		(pin "T30"
		)
		(pin "R15"
		)
		(pin "Y34"
		)
		(pin "AD8"
		)
		(pin "W13"
		)
		(pin "H38"
		)
		(pin "V34"
		)
		(pin "AD42"
		)
		(pin "B28"
		)
		(pin "R13"
		)
		(pin "V10"
		)
		(pin "D20"
		)
		(pin "A17"
		)
		(pin "AD6"
		)
		(pin "M38"
		)
		(pin "T10"
		)
		(pin "M26"
		)
		(pin "U29"
		)
		(pin "F12"
		)
		(pin "AD38"
		)
		(pin "F38"
		)
		(pin "B8"
		)
		(pin "Y30"
		)
		(pin "H8"
		)
		(pin "C35"
		)
		(pin "AD28"
		)
		(pin "AD14"
		)
		(pin "W29"
		)
		(pin "W35"
		)
		(pin "H2"
		)
		(pin "D16"
		)
		(pin "M6"
		)
		(pin "V24"
		)
		(pin "AC19"
		)
		(pin "J35"
		)
		(pin "R23"
		)
		(pin "M8"
		)
		(pin "J37"
		)
		(pin "AB12"
		)
		(pin "AC1"
		)
		(pin "L23"
		)
		(pin "N9"
		)
		(pin "Y32"
		)
		(pin "J15"
		)
		(pin "G33"
		)
		(pin "A35"
		)
		(pin "T14"
		)
		(pin "G5"
		)
		(pin "U23"
		)
		(pin "W31"
		)
		(pin "AB8"
		)
		(pin "AA17"
		)
		(pin "A39"
		)
		(pin "AB4"
		)
		(pin "H40"
		)
		(pin "K12"
		)
		(pin "G37"
		)
		(pin "T6"
		)
		(pin "N23"
		)
		(pin "A33"
		)
		(pin "AD36"
		)
		(pin "W1"
		)
		(pin "V20"
		)
		(pin "E23"
		)
		(pin "V36"
		)
		(pin "Y38"
		)
		(pin "V42"
		)
		(pin "AC21"
		)
		(pin "C3"
		)
		(pin "AB18"
		)
		(pin "AA19"
		)
		(pin "R31"
		)
		(pin "F18"
		)
		(pin "B12"
		)
		(pin "N5"
		)
		(pin "B6"
		)
		(pin "Y28"
		)
		(pin "D8"
		)
		(pin "A37"
		)
		(pin "N21"
		)
		(pin "AA11"
		)
		(pin "T4"
		)
		(pin "N35"
		)
		(pin "A41"
		)
		(pin "B18"
		)
		(pin "AB26"
		)
		(pin "U3"
		)
		(pin "D32"
		)
		(pin "D14"
		)
		(pin "L31"
		)
		(pin "K2"
		)
		(pin "T36"
		)
		(pin "AB22"
		)
		(pin "T42"
		)
		(pin "T32"
		)
		(pin "AB28"
		)
		(pin "V26"
		)
		(pin "U31"
		)
		(pin "AB24"
		)
		(pin "R9"
		)
		(pin "A9"
		)
		(pin "AC11"
		)
		(pin "B30"
		)
		(pin "AC17"
		)
		(pin "T18"
		)
		(pin "A27"
		)
		(pin "AA25"
		)
		(pin "U27"
		)
		(pin "Y14"
		)
		(pin "AB38"
		)
		(pin "AA29"
		)
		(pin "C39"
		)
		(pin "T24"
		)
		(pin "L7"
		)
		(pin "J31"
		)
		(pin "P30"
		)
		(pin "E13"
		)
		(pin "G39"
		)
		(pin "AB42"
		)
		(pin "E25"
		)
		(pin "Y10"
		)
		(pin "T40"
		)
		(pin "V22"
		)
		(pin "E1"
		)
		(pin "K24"
		)
		(pin "J17"
		)
		(pin "Y20"
		)
		(pin "E39"
		)
		(pin "AC31"
		)
		(pin "AB32"
		)
		(pin "A5"
		)
		(pin "AB30"
		)
		(pin "L17"
		)
		(pin "F20"
		)
		(pin "N19"
		)
		(pin "N41"
		)
		(pin "U33"
		)
		(pin "E11"
		)
		(pin "J1"
		)
		(pin "H14"
		)
		(pin "G29"
		)
		(pin "E17"
		)
		(pin "K6"
		)
		(pin "D10"
		)
		(pin "P6"
		)
		(pin "K32"
		)
		(pin "AA15"
		)
		(pin "M32"
		)
		(pin "J25"
		)
		(pin "K34"
		)
		(pin "AA31"
		)
		(pin "B24"
		)
		(pin "A25"
		)
		(pin "G25"
		)
		(pin "N11"
		)
		(pin "E5"
		)
		(pin "AD22"
		)
		(pin "K42"
		)
		(pin "D6"
		)
		(pin "E27"
		)
		(pin "N7"
		)
		(pin "N3"
		)
		(pin "J21"
		)
		(pin "H20"
		)
		(pin "H12"
		)
		(pin "F4"
		)
		(pin "U25"
		)
		(pin "K4"
		)
		(pin "M22"
		)
		(pin "P24"
		)
		(pin "AA3"
		)
		(pin "E35"
		)
		(pin "AC13"
		)
		(pin "B38"
		)
		(pin "W37"
		)
		(pin "M34"
		)
		(pin "G1"
		)
		(pin "AD26"
		)
		(pin "N37"
		)
		(pin "E37"
		)
		(pin "W39"
		)
		(pin "AA35"
		)
		(pin "E19"
		)
		(pin "H42"
		)
		(pin "AC39"
		)
		(pin "AD2"
		)
		(pin "AA37"
		)
		(pin "H22"
		)
		(pin "B26"
		)
		(pin "A15"
		)
		(pin "K28"
		)
		(pin "AA39"
		)
		(pin "P40"
		)
		(pin "N39"
		)
		(pin "AA9"
		)
		(pin "K26"
		)
		(pin "B42"
		)
		(pin "Y12"
		)
		(pin "V8"
		)
		(pin "H10"
		)
		(pin "AD40"
		)
		(pin "J11"
		)
		(pin "V38"
		)
		(pin "V40"
		)
		(pin "F2"
		)
		(pin "P34"
		)
		(pin "AA23"
		)
		(pin "T26"
		)
		(pin "D4"
		)
		(pin "F22"
		)
		(pin "M42"
		)
		(pin "J9"
		)
		(pin "F8"
		)
		(pin "N1"
		)
		(pin "AD20"
		)
		(pin "V28"
		)
		(pin "AA5"
		)
		(pin "AC5"
		)
		(pin "AD4"
		)
		(pin "AB2"
		)
		(pin "AA1"
		)
		(pin "P2"
		)
		(pin "R1"
		)
		(pin "P42"
		)
		(pin "AC3"
		)
		(pin "G11"
		)
		(pin "N33"
		)
		(pin "U39"
		)
		(pin "J5"
		)
		(pin "R33"
		)
		(pin "W27"
		)
		(pin "W7"
		)
		(pin "L5"
		)
		(pin "R7"
		)
		(pin "L3"
		)
		(pin "B36"
		)
		(pin "P4"
		)
		(pin "AA7"
		)
		(pin "M2"
		)
		(pin "C1"
		)
		(pin "AC25"
		)
		(pin "AB40"
		)
		(pin "E15"
		)
		(pin "H24"
		)
		(pin "P36"
		)
		(pin "V6"
		)
		(pin "R25"
		)
		(pin "A11"
		)
		(pin "G23"
		)
		(pin "AD34"
		)
		(pin "Y24"
		)
		(pin "Y18"
		)
		(pin "V32"
		)
		(pin "J33"
		)
		(pin "L15"
		)
		(pin "C7"
		)
		(pin "J41"
		)
		(pin "AA33"
		)
		(pin "M4"
		)
		(pin "E9"
		)
		(pin "V30"
		)
		(pin "AC15"
		)
		(pin "AB16"
		)
		(pin "L41"
		)
		(pin "AC29"
		)
		(pin "N25"
		)
		(pin "F10"
		)
		(pin "Y16"
		)
		(pin "K30"
		)
		(pin "AD16"
		)
		(pin "AD18"
		)
		(pin "H18"
		)
		(pin "AB10"
		)
		(pin "G27"
		)
		(pin "M40"
		)
		(pin "B34"
		)
		(pin "B10"
		)
		(pin "L11"
		)
		(pin "J23"
		)
		(pin "AB36"
		)
		(pin "Y22"
		)
		(pin "AD24"
		)
		(pin "D34"
		)
		(pin "E41"
		)
		(pin "L37"
		)
		(pin "R41"
		)
		(pin "G7"
		)
		(pin "AB34"
		)
		(pin "T38"
		)
		(pin "AB20"
		)
		(pin "G17"
		)
		(pin "M36"
		)
		(pin "G9"
		)
		(pin "C21"
		)
		(pin "AC37"
		)
		(pin "AC35"
		)
		(pin "D18"
		)
		(pin "D22"
		)
		(instances
			(project "OCuLink to 10GbE adapter"
				(path ""
					(reference "U9")
					(unit 1)
				)
			)
		)
	)
)
